FILE_TYPE = MACRO_DRAWING;
SET COLOR_WIRE YELLOW;
SET COLOR_PROP ORANGE;
SET COLOR_DOT WHITE;
SET COLOR_ARC YELLOW;
SET COLOR_BODY GREEN;
SET COLOR_NOTE PURPLE;
SET PROP_DISPLAY VALUE;
SET PAGE_NUMBER P111;
FORCEADD DS125BR111RTWR..1
(-4725 5325);
FORCEPROP 1 LAST LOCATION U6000
J 0
(-5095 6318);
DISPLAY 0.723404 (-5095 6318);
PAINT GREEN (-5095 6318);
FORCEPROP 2 LAST SEC 1
J 0
(-5075 6475);
DISPLAY 0.680851 (-5075 6475);
PAINT MONO (-5075 6475);
DISPLAY INVISIBLE (-5075 6475);
FORCEPROP 2 LASTPIN (-5250 5175) $PN 3
J 2
(-5260 5185);
DISPLAY 0.680851 (-5260 5185);
PAINT MONO (-5260 5185);
FORCEPROP 2 LASTPIN (-5250 5625) $PN 10
J 2
(-5260 5635);
DISPLAY 0.680851 (-5260 5635);
PAINT MONO (-5260 5635);
FORCEPROP 2 LASTPIN (-5250 5575) $PN 9
J 2
(-5260 5585);
DISPLAY 0.680851 (-5260 5585);
PAINT MONO (-5260 5585);
FORCEPROP 2 LASTPIN (-5250 5475) $PN 1
J 2
(-5260 5485);
DISPLAY 0.680851 (-5260 5485);
PAINT MONO (-5260 5485);
FORCEPROP 2 LASTPIN (-5250 5525) $PN 2
J 2
(-5260 5535);
DISPLAY 0.680851 (-5260 5535);
PAINT MONO (-5260 5535);
FORCEPROP 2 LASTPIN (-5250 4975) $PN 24
J 2
(-5260 4985);
DISPLAY 0.680851 (-5260 4985);
PAINT MONO (-5260 4985);
FORCEPROP 2 LASTPIN (-5250 4925) $PN 23
J 2
(-5260 4935);
DISPLAY 0.680851 (-5260 4935);
PAINT MONO (-5260 4935);
FORCEPROP 2 LASTPIN (-5250 4825) $PN 11
J 2
(-5260 4835);
DISPLAY 0.680851 (-5260 4835);
PAINT MONO (-5260 4835);
FORCEPROP 2 LASTPIN (-5250 4775) $PN 12
J 2
(-5260 4785);
DISPLAY 0.680851 (-5260 4785);
PAINT MONO (-5260 4785);
FORCEPROP 2 LASTPIN (-4200 4975) $PN 7
J 0
(-4190 4985);
DISPLAY 0.680851 (-4190 4985);
PAINT MONO (-4190 4985);
FORCEPROP 2 LASTPIN (-4200 4925) $PN 8
J 0
(-4190 4935);
DISPLAY 0.680851 (-4190 4935);
PAINT MONO (-4190 4935);
FORCEPROP 2 LASTPIN (-4200 4825) $PN 20
J 0
(-4190 4835);
DISPLAY 0.680851 (-4190 4835);
PAINT MONO (-4190 4835);
FORCEPROP 2 LASTPIN (-4200 4775) $PN 19
J 0
(-4190 4785);
DISPLAY 0.680851 (-4190 4785);
PAINT MONO (-4190 4785);
FORCEPROP 2 LASTPIN (-4200 5225) $PN 6
J 0
(-4190 5235);
DISPLAY 0.680851 (-4190 5235);
PAINT MONO (-4190 5235);
FORCEPROP 2 LASTPIN (-4200 5825) $PN 13
J 0
(-4190 5835);
DISPLAY 0.680851 (-4190 5835);
PAINT MONO (-4190 5835);
FORCEPROP 2 LASTPIN (-4200 5375) $PN 18
J 0
(-4190 5385);
DISPLAY 0.680851 (-4190 5385);
PAINT MONO (-4190 5385);
FORCEPROP 2 LASTPIN (-5250 5075) $PN 5
J 2
(-5260 5085);
DISPLAY 0.680851 (-5260 5085);
PAINT MONO (-5260 5085);
FORCEPROP 2 LASTPIN (-4200 5675) $PN 14
J 0
(-4190 5685);
DISPLAY 0.680851 (-4190 5685);
PAINT MONO (-4190 5685);
FORCEPROP 2 LASTPIN (-5250 5125) $PN 4
J 2
(-5260 5135);
DISPLAY 0.680851 (-5260 5135);
PAINT MONO (-5260 5135);
FORCEPROP 2 LASTPIN (-4200 4675) $PN 25
J 0
(-4190 4685);
DISPLAY 0.680851 (-4190 4685);
PAINT MONO (-4190 4685);
FORCEPROP 2 LASTPIN (-5250 5875) $PN 21
J 2
(-5260 5885);
DISPLAY 0.680851 (-5260 5885);
PAINT MONO (-5260 5885);
FORCEPROP 2 LASTPIN (-5250 5825) $PN 22
J 2
(-5260 5835);
DISPLAY 0.680851 (-5260 5835);
PAINT MONO (-5260 5835);
FORCEPROP 2 LASTPIN (-5250 5725) $PN 16
J 2
(-5260 5735);
DISPLAY 0.680851 (-5260 5735);
PAINT MONO (-5260 5735);
FORCEPROP 2 LASTPIN (-5250 5925) $PN 15
J 2
(-5260 5935);
DISPLAY 0.680851 (-5260 5935);
PAINT MONO (-5260 5935);
FORCEPROP 2 LASTPIN (-4200 5975) $PN 17
J 0
(-4190 5985);
DISPLAY 0.680851 (-4190 5985);
PAINT MONO (-4190 5985);
FORCEPROP 2 LAST ROOM PCIE REDRIVER BOM2
J 0
(-5075 6475);
DISPLAY 0.680851 (-5075 6475);
PAINT RED (-5075 6475);
FORCEPROP 2 LAST PART_TYPE SMLF
J 0
(-5075 6425);
DISPLAY 0.680851 (-5075 6425);
FORCEPROP 2 LAST VALUE DS125BR111RTWR
J 0
(-5075 6375);
DISPLAY 0.680851 (-5075 6375);
FORCEPROP 1 LAST MATERIAL IC
J 0
(-5095 6044);
DISPLAY 0.723404 (-5095 6044);
PAINT GREEN (-5095 6044);
FORCEPROP 2 LAST SEC_TYPE 
J 0
(-5075 6475);
DISPLAY 0.680851 (-5075 6475);
DISPLAY INVISIBLE (-5075 6475);
FORCEPROP 2 LAST CDS_LIB pure_quanta
J 0
(-4725 5325);
DISPLAY INVISIBLE (-4725 5325);
FORCEPROP 1 LAST NEEDS_NO_SIZE TRUE
J 0
(-4725 5325);
DISPLAY 0.723404 (-4725 5325);
PAINT GREEN (-4725 5325);
DISPLAY INVISIBLE (-4725 5325);
FORCEPROP 1 LAST CDS_LMAN_SYM_OUTLINE -375,700,375,-700
J 0
(-4725 5325);
DISPLAY 0.468085 (-4725 5325);
PAINT GREEN (-4725 5325);
DISPLAY INVISIBLE (-4725 5325);
FORCEPROP 1 LAST PATH I1
J 0
(-4725 5325);
DISPLAY 0.723404 (-4725 5325);
PAINT GREEN (-4725 5325);
DISPLAY INVISIBLE (-4725 5325);
FORCEPROP 1 LAST PART_NUMBER AL000125003
J 0
(-5095 6171);
DISPLAY 0.723404 (-5095 6171);
PAINT GREEN (-5095 6171);
DISPLAY INVISIBLE (-5095 6171);
FORCEADD OFFPAGE..4
R 2
(-6800 5525);
FORCEPROP 2 LAST $XR0 112 
J 0
(-7082 5525);
DISPLAY 0.638298 (-7082 5525);
PAINT MONO (-7082 5525);
FORCEPROP 2 LAST CDS_LIB standard
J 0
(-6800 5525);
DISPLAY INVISIBLE (-6800 5525);
FORCEPROP 1 LAST OFFPAGE TRUE
J 2
(-7125 5400);
DISPLAY 0.872340 (-7125 5400);
PAINT GREEN (-7125 5400);
DISPLAY INVISIBLE (-7125 5400);
FORCEPROP 1 LAST COMMENT_BODY TRUE
J 2
(-6775 5425);
DISPLAY 0.872340 (-6775 5425);
PAINT GREEN (-6775 5425);
DISPLAY INVISIBLE (-6775 5425);
FORCEPROP 2 LAST PATH I10
J 0
(-6750 5600);
DISPLAY 0.680851 (-6750 5600);
DISPLAY INVISIBLE (-6750 5600);
FORCEADD OFFPAGE..4
R 2
(-6800 5475);
FORCEPROP 2 LAST $XR0 112 
J 0
(-7082 5475);
DISPLAY 0.638298 (-7082 5475);
PAINT MONO (-7082 5475);
FORCEPROP 2 LAST CDS_LIB standard
J 0
(-6800 5475);
DISPLAY INVISIBLE (-6800 5475);
FORCEPROP 1 LAST OFFPAGE TRUE
J 2
(-7125 5350);
DISPLAY 0.872340 (-7125 5350);
PAINT GREEN (-7125 5350);
DISPLAY INVISIBLE (-7125 5350);
FORCEPROP 1 LAST COMMENT_BODY TRUE
J 2
(-6775 5375);
DISPLAY 0.872340 (-6775 5375);
PAINT GREEN (-6775 5375);
DISPLAY INVISIBLE (-6775 5375);
FORCEPROP 2 LAST PATH I11
J 0
(-6750 5550);
DISPLAY 0.680851 (-6750 5550);
DISPLAY INVISIBLE (-6750 5550);
FORCEADD Q_RES..2
(-7525 4875);
FORCEPROP 1 LAST LOCATION R6160
J 0
(-7480 5000);
DISPLAY 0.638298 (-7480 5000);
FORCEPROP 0 LAST $SEC 1
J 0
(-7475 5050);
DISPLAY 0.680851 (-7475 5050);
PAINT MONO (-7475 5050);
DISPLAY INVISIBLE (-7475 5050);
FORCEPROP 0 LAST CDS_SEC 1
J 0
(-7475 5050);
DISPLAY 0.680851 (-7475 5050);
DISPLAY INVISIBLE (-7475 5050);
FORCEPROP 1 LASTPIN (-7525 4975) $PN 1
J 0
(-7520 4937);
DISPLAY 0.787234 (-7520 4937);
PAINT MONO (-7520 4937);
FORCEPROP 1 LASTPIN (-7525 4775) $PN 2
J 0
(-7520 4785);
DISPLAY 0.787234 (-7520 4785);
PAINT MONO (-7520 4785);
FORCEPROP 1 LAST WATTAGE 1/16W
J 0
(-7485 4850);
DISPLAY 0.638298 (-7485 4850);
FORCEPROP 1 LAST VALUE 1K
J 0
(-7480 4950);
DISPLAY 0.638298 (-7480 4950);
FORCEPROP 1 LAST MATERIAL CHIP
J 0
(-7485 4800);
DISPLAY 0.638298 (-7485 4800);
FORCEPROP 1 LAST PACK_TYPE 0402LF
J 0
(-7485 4700);
DISPLAY 0.638298 (-7485 4700);
FORCEPROP 1 LAST TOLERANCE 1%
J 0
(-7480 4900);
DISPLAY 0.638298 (-7480 4900);
FORCEPROP 2 LAST ROOM PCIE REDRIVER BOM2
J 0
(-7475 5050);
DISPLAY 0.553191 (-7475 5050);
PAINT RED (-7475 5050);
FORCEPROP 2 LAST CDS_LIB pure_quanta
J 0
(-7525 4875);
DISPLAY INVISIBLE (-7525 4875);
FORCEPROP 1 LAST PATH I12
J 0
(-7475 5050);
DISPLAY 0.978723 (-7475 5050);
PAINT WHITE (-7475 5050);
DISPLAY INVISIBLE (-7475 5050);
FORCEPROP 1 LAST PART_NUMBER CS21002FB06
J 0
(-7485 4750);
DISPLAY 0.638298 (-7485 4750);
DISPLAY INVISIBLE (-7485 4750);
FORCEADD UNIVERSAL_GND..1
(-7525 4575);
FORCEPROP 3 LASTPIN (-7525 4625) SIG_NAME GND\g
J 0
(-7515 4635);
DISPLAY 0.659574 (-7515 4635);
PAINT MONO (-7515 4635);
DISPLAY INVISIBLE (-7515 4635);
FORCEPROP 2 LAST CDS_LIB pure_quanta_power
J 0
(-7525 4575);
DISPLAY INVISIBLE (-7525 4575);
FORCEPROP 1 LAST HDL_POWER GND
J 1
(-7500 4500);
DISPLAY 0.872340 (-7500 4500);
PAINT GREEN (-7500 4500);
DISPLAY INVISIBLE (-7500 4500);
FORCEPROP 1 LAST PATH I13
J 0
(-7450 4575);
DISPLAY 0.872340 (-7450 4575);
PAINT AQUA (-7450 4575);
DISPLAY INVISIBLE (-7450 4575);
FORCEADD OFFPAGE..4
R 2
(-6625 5125);
FORCEPROP 2 LAST $XR0 112 
J 0
(-6877 5125);
DISPLAY 0.638298 (-6877 5125);
PAINT MONO (-6877 5125);
FORCEPROP 2 LAST CDS_LIB standard
J 0
(-6625 5125);
DISPLAY INVISIBLE (-6625 5125);
FORCEPROP 1 LAST OFFPAGE TRUE
J 2
(-6950 5000);
DISPLAY 0.872340 (-6950 5000);
PAINT GREEN (-6950 5000);
DISPLAY INVISIBLE (-6950 5000);
FORCEPROP 1 LAST COMMENT_BODY TRUE
J 2
(-6600 5025);
DISPLAY 0.872340 (-6600 5025);
PAINT GREEN (-6600 5025);
DISPLAY INVISIBLE (-6600 5025);
FORCEPROP 2 LAST PATH I14
J 0
(-6575 5200);
DISPLAY 0.680851 (-6575 5200);
DISPLAY INVISIBLE (-6575 5200);
FORCEADD OFFPAGE..4
R 2
(-6625 5075);
FORCEPROP 2 LAST $XR0 112 
J 0
(-6877 5075);
DISPLAY 0.638298 (-6877 5075);
PAINT MONO (-6877 5075);
FORCEPROP 2 LAST CDS_LIB standard
J 0
(-6625 5075);
DISPLAY INVISIBLE (-6625 5075);
FORCEPROP 1 LAST OFFPAGE TRUE
J 2
(-6950 4950);
DISPLAY 0.872340 (-6950 4950);
PAINT GREEN (-6950 4950);
DISPLAY INVISIBLE (-6950 4950);
FORCEPROP 1 LAST COMMENT_BODY TRUE
J 2
(-6600 4975);
DISPLAY 0.872340 (-6600 4975);
PAINT GREEN (-6600 4975);
DISPLAY INVISIBLE (-6600 4975);
FORCEPROP 2 LAST PATH I15
J 0
(-6575 5150);
DISPLAY 0.680851 (-6575 5150);
DISPLAY INVISIBLE (-6575 5150);
FORCEADD OFFPAGE..4
R 2
(-6600 4975);
FORCEPROP 2 LAST $XR0 113 
J 0
(-6852 4975);
DISPLAY 0.638298 (-6852 4975);
PAINT MONO (-6852 4975);
FORCEPROP 2 LAST CDS_LIB standard
J 0
(-6600 4975);
DISPLAY INVISIBLE (-6600 4975);
FORCEPROP 1 LAST OFFPAGE TRUE
J 2
(-6925 4850);
DISPLAY 0.872340 (-6925 4850);
PAINT GREEN (-6925 4850);
DISPLAY INVISIBLE (-6925 4850);
FORCEPROP 1 LAST COMMENT_BODY TRUE
J 2
(-6575 4875);
DISPLAY 0.872340 (-6575 4875);
PAINT GREEN (-6575 4875);
DISPLAY INVISIBLE (-6575 4875);
FORCEPROP 2 LAST PATH I16
J 0
(-6550 5050);
DISPLAY 0.680851 (-6550 5050);
DISPLAY INVISIBLE (-6550 5050);
FORCEADD OFFPAGE..4
R 2
(-6600 4925);
FORCEPROP 2 LAST $XR0 113 
J 0
(-6852 4925);
DISPLAY 0.638298 (-6852 4925);
PAINT MONO (-6852 4925);
FORCEPROP 2 LAST CDS_LIB standard
J 0
(-6600 4925);
DISPLAY INVISIBLE (-6600 4925);
FORCEPROP 1 LAST OFFPAGE TRUE
J 2
(-6925 4800);
DISPLAY 0.872340 (-6925 4800);
PAINT GREEN (-6925 4800);
DISPLAY INVISIBLE (-6925 4800);
FORCEPROP 1 LAST COMMENT_BODY TRUE
J 2
(-6575 4825);
DISPLAY 0.872340 (-6575 4825);
PAINT GREEN (-6575 4825);
DISPLAY INVISIBLE (-6575 4825);
FORCEPROP 2 LAST PATH I17
J 0
(-6550 5000);
DISPLAY 0.680851 (-6550 5000);
DISPLAY INVISIBLE (-6550 5000);
FORCEADD OFFPAGE..4
R 2
(-6600 4825);
FORCEPROP 2 LAST $XR0 113 
J 0
(-6852 4825);
DISPLAY 0.638298 (-6852 4825);
PAINT MONO (-6852 4825);
FORCEPROP 2 LAST CDS_LIB standard
J 0
(-6600 4825);
DISPLAY INVISIBLE (-6600 4825);
FORCEPROP 1 LAST OFFPAGE TRUE
J 2
(-6925 4700);
DISPLAY 0.872340 (-6925 4700);
PAINT GREEN (-6925 4700);
DISPLAY INVISIBLE (-6925 4700);
FORCEPROP 1 LAST COMMENT_BODY TRUE
J 2
(-6575 4725);
DISPLAY 0.872340 (-6575 4725);
PAINT GREEN (-6575 4725);
DISPLAY INVISIBLE (-6575 4725);
FORCEPROP 2 LAST PATH I18
J 0
(-6550 4900);
DISPLAY 0.680851 (-6550 4900);
DISPLAY INVISIBLE (-6550 4900);
FORCEADD OFFPAGE..4
R 2
(-6600 4775);
FORCEPROP 2 LAST $XR0 113 
J 0
(-6852 4775);
DISPLAY 0.638298 (-6852 4775);
PAINT MONO (-6852 4775);
FORCEPROP 2 LAST CDS_LIB standard
J 0
(-6600 4775);
DISPLAY INVISIBLE (-6600 4775);
FORCEPROP 1 LAST OFFPAGE TRUE
J 2
(-6925 4650);
DISPLAY 0.872340 (-6925 4650);
PAINT GREEN (-6925 4650);
DISPLAY INVISIBLE (-6925 4650);
FORCEPROP 1 LAST COMMENT_BODY TRUE
J 2
(-6575 4675);
DISPLAY 0.872340 (-6575 4675);
PAINT GREEN (-6575 4675);
DISPLAY INVISIBLE (-6575 4675);
FORCEPROP 2 LAST PATH I19
J 0
(-6550 4850);
DISPLAY 0.680851 (-6550 4850);
DISPLAY INVISIBLE (-6550 4850);
FORCEADD UNIVERSAL_POWER..1
(-6125 6425);
FORCEPROP 3 LASTPIN (-6125 6375) SIG_NAME P3V3_AUX\g
J 0
(-6115 6385);
DISPLAY 0.659574 (-6115 6385);
PAINT MONO (-6115 6385);
DISPLAY INVISIBLE (-6115 6385);
FORCEPROP 1 LAST HDL_POWER P3V3_AUX
J 1
(-6125 6475);
DISPLAY 0.872340 (-6125 6475);
PAINT GREEN (-6125 6475);
FORCEPROP 2 LAST CDS_LIB pure_quanta_power
J 0
(-6125 6425);
DISPLAY INVISIBLE (-6125 6425);
FORCEPROP 1 LAST PATH I2
J 0
(-6075 6450);
DISPLAY 0.872340 (-6075 6450);
PAINT AQUA (-6075 6450);
DISPLAY INVISIBLE (-6075 6450);
FORCEADD OFFPAGE..4
(-3225 5975);
FORCEPROP 2 LAST $XR0 112 
J 0
(-3039 5975);
DISPLAY 0.638298 (-3039 5975);
PAINT MONO (-3039 5975);
FORCEPROP 2 LAST CDS_LIB standard
J 0
(-3225 5975);
DISPLAY INVISIBLE (-3225 5975);
FORCEPROP 1 LAST OFFPAGE TRUE
J 0
(-2900 5850);
DISPLAY 0.872340 (-2900 5850);
PAINT GREEN (-2900 5850);
DISPLAY INVISIBLE (-2900 5850);
FORCEPROP 1 LAST COMMENT_BODY TRUE
J 0
(-3250 5875);
DISPLAY 0.872340 (-3250 5875);
PAINT GREEN (-3250 5875);
DISPLAY INVISIBLE (-3250 5875);
FORCEPROP 2 LAST PATH I20
J 0
(-3050 6050);
DISPLAY 0.680851 (-3050 6050);
DISPLAY INVISIBLE (-3050 6050);
FORCEADD OFFPAGE..4
(-3225 5675);
FORCEPROP 2 LAST $XR0 112 
J 0
(-3039 5675);
DISPLAY 0.638298 (-3039 5675);
PAINT MONO (-3039 5675);
FORCEPROP 2 LAST CDS_LIB standard
J 0
(-3225 5675);
DISPLAY INVISIBLE (-3225 5675);
FORCEPROP 1 LAST OFFPAGE TRUE
J 0
(-2900 5550);
DISPLAY 0.872340 (-2900 5550);
PAINT GREEN (-2900 5550);
DISPLAY INVISIBLE (-2900 5550);
FORCEPROP 1 LAST COMMENT_BODY TRUE
J 0
(-3250 5575);
DISPLAY 0.872340 (-3250 5575);
PAINT GREEN (-3250 5575);
DISPLAY INVISIBLE (-3250 5575);
FORCEPROP 2 LAST PATH I21
J 0
(-3050 5750);
DISPLAY 0.680851 (-3050 5750);
DISPLAY INVISIBLE (-3050 5750);
FORCEADD OFFPAGE..4
(-3225 5375);
FORCEPROP 2 LAST $XR0 112 
J 0
(-3039 5375);
DISPLAY 0.638298 (-3039 5375);
PAINT MONO (-3039 5375);
FORCEPROP 2 LAST CDS_LIB standard
J 0
(-3225 5375);
DISPLAY INVISIBLE (-3225 5375);
FORCEPROP 1 LAST OFFPAGE TRUE
J 0
(-2900 5250);
DISPLAY 0.872340 (-2900 5250);
PAINT GREEN (-2900 5250);
DISPLAY INVISIBLE (-2900 5250);
FORCEPROP 1 LAST COMMENT_BODY TRUE
J 0
(-3250 5275);
DISPLAY 0.872340 (-3250 5275);
PAINT GREEN (-3250 5275);
DISPLAY INVISIBLE (-3250 5275);
FORCEPROP 2 LAST PATH I22
J 0
(-3050 5450);
DISPLAY 0.680851 (-3050 5450);
DISPLAY INVISIBLE (-3050 5450);
FORCEADD Q_RES..1
(-3275 5225);
FORCEPROP 1 LAST LOCATION R6162
J 0
(-3500 5225);
DISPLAY 0.638298 (-3500 5225);
FORCEPROP 0 LAST $SEC 1
J 0
(-3100 5275);
DISPLAY 0.680851 (-3100 5275);
PAINT MONO (-3100 5275);
DISPLAY INVISIBLE (-3100 5275);
FORCEPROP 0 LAST CDS_SEC 1
J 0
(-3100 5275);
DISPLAY 0.680851 (-3100 5275);
DISPLAY INVISIBLE (-3100 5275);
FORCEPROP 1 LASTPIN (-3375 5225) $PN 1
J 0
(-3363 5237);
DISPLAY 0.787234 (-3363 5237);
PAINT MONO (-3363 5237);
FORCEPROP 1 LASTPIN (-3175 5225) $PN 2
J 0
(-3213 5237);
DISPLAY 0.787234 (-3213 5237);
PAINT MONO (-3213 5237);
FORCEPROP 1 LAST MATERIAL CHIP
J 0
(-3400 5100);
DISPLAY 0.595745 (-3400 5100);
FORCEPROP 1 LAST WATTAGE 1/16W
J 2
(-3075 5100);
DISPLAY 0.595745 (-3075 5100);
FORCEPROP 2 LAST ROOM PCIE REDRIVER BOM2
J 0
(-3475 5300);
DISPLAY 0.553191 (-3475 5300);
PAINT RED (-3475 5300);
FORCEPROP 1 LAST PACK_TYPE 0402LF
J 0
(-3200 5150);
DISPLAY 0.595745 (-3200 5150);
FORCEPROP 1 LAST TOLERANCE 5%
J 0
(-3100 5225);
DISPLAY 0.595745 (-3100 5225);
FORCEPROP 1 LAST VALUE 0
J 2
(-3125 5225);
DISPLAY 0.595745 (-3125 5225);
FORCEPROP 2 LAST CDS_LIB pure_quanta
J 0
(-3275 5225);
DISPLAY INVISIBLE (-3275 5225);
FORCEPROP 1 LAST PATH I23
J 0
(-3325 5375);
DISPLAY 0.978723 (-3325 5375);
PAINT WHITE (-3325 5375);
DISPLAY INVISIBLE (-3325 5375);
FORCEPROP 1 LAST PART_NUMBER CS00002JB13
J 0
(-3575 5150);
DISPLAY 0.595745 (-3575 5150);
DISPLAY INVISIBLE (-3575 5150);
FORCEADD OFFPAGE..4
(-2125 5225);
FORCEPROP 2 LAST $XR1 234 
J 0
(-1819 5225);
DISPLAY 0.638298 (-1819 5225);
PAINT MONO (-1819 5225);
FORCEPROP 2 LAST $XR0 111 
J 0
(-1939 5225);
DISPLAY 0.638298 (-1939 5225);
PAINT MONO (-1939 5225);
FORCEPROP 2 LAST CDS_LIB standard
J 0
(-2125 5225);
DISPLAY INVISIBLE (-2125 5225);
FORCEPROP 1 LAST OFFPAGE TRUE
J 0
(-1800 5100);
DISPLAY 0.872340 (-1800 5100);
PAINT GREEN (-1800 5100);
DISPLAY INVISIBLE (-1800 5100);
FORCEPROP 1 LAST COMMENT_BODY TRUE
J 0
(-2150 5125);
DISPLAY 0.872340 (-2150 5125);
PAINT GREEN (-2150 5125);
DISPLAY INVISIBLE (-2150 5125);
FORCEPROP 2 LAST PATH I24
J 0
(-1950 5300);
DISPLAY 0.680851 (-1950 5300);
DISPLAY INVISIBLE (-1950 5300);
FORCEADD OFFPAGE..2
(-3250 4975);
FORCEPROP 2 LAST $XR0 113 
J 0
(-3061 4975);
DISPLAY 0.638298 (-3061 4975);
PAINT MONO (-3061 4975);
FORCEPROP 2 LAST CDS_LIB standard
J 0
(-3250 4975);
DISPLAY INVISIBLE (-3250 4975);
FORCEPROP 1 LAST OFFPAGE TRUE
J 0
(-2925 4850);
DISPLAY 0.872340 (-2925 4850);
PAINT AQUA (-2925 4850);
DISPLAY INVISIBLE (-2925 4850);
FORCEPROP 1 LAST COMMENT_BODY TRUE
J 0
(-3295 4880);
DISPLAY 0.872340 (-3295 4880);
PAINT GREEN (-3295 4880);
DISPLAY INVISIBLE (-3295 4880);
FORCEPROP 2 LAST PATH I25
J 0
(-3075 5050);
DISPLAY 0.680851 (-3075 5050);
DISPLAY INVISIBLE (-3075 5050);
FORCEADD OFFPAGE..2
(-3250 4925);
FORCEPROP 2 LAST $XR0 113 
J 0
(-3061 4925);
DISPLAY 0.638298 (-3061 4925);
PAINT MONO (-3061 4925);
FORCEPROP 2 LAST CDS_LIB standard
J 0
(-3250 4925);
DISPLAY INVISIBLE (-3250 4925);
FORCEPROP 1 LAST OFFPAGE TRUE
J 0
(-2925 4800);
DISPLAY 0.872340 (-2925 4800);
PAINT AQUA (-2925 4800);
DISPLAY INVISIBLE (-2925 4800);
FORCEPROP 1 LAST COMMENT_BODY TRUE
J 0
(-3295 4830);
DISPLAY 0.872340 (-3295 4830);
PAINT GREEN (-3295 4830);
DISPLAY INVISIBLE (-3295 4830);
FORCEPROP 2 LAST PATH I26
J 0
(-3075 5000);
DISPLAY 0.680851 (-3075 5000);
DISPLAY INVISIBLE (-3075 5000);
FORCEADD OFFPAGE..2
(-3250 4825);
FORCEPROP 2 LAST $XR0 113 
J 0
(-3061 4825);
DISPLAY 0.638298 (-3061 4825);
PAINT MONO (-3061 4825);
FORCEPROP 2 LAST CDS_LIB standard
J 0
(-3250 4825);
DISPLAY INVISIBLE (-3250 4825);
FORCEPROP 1 LAST OFFPAGE TRUE
J 0
(-2925 4700);
DISPLAY 0.872340 (-2925 4700);
PAINT AQUA (-2925 4700);
DISPLAY INVISIBLE (-2925 4700);
FORCEPROP 1 LAST COMMENT_BODY TRUE
J 0
(-3295 4730);
DISPLAY 0.872340 (-3295 4730);
PAINT GREEN (-3295 4730);
DISPLAY INVISIBLE (-3295 4730);
FORCEPROP 2 LAST PATH I27
J 0
(-3075 4900);
DISPLAY 0.680851 (-3075 4900);
DISPLAY INVISIBLE (-3075 4900);
FORCEADD OFFPAGE..2
(-3250 4775);
FORCEPROP 2 LAST $XR0 113 
J 0
(-3061 4775);
DISPLAY 0.638298 (-3061 4775);
PAINT MONO (-3061 4775);
FORCEPROP 2 LAST CDS_LIB standard
J 0
(-3250 4775);
DISPLAY INVISIBLE (-3250 4775);
FORCEPROP 1 LAST OFFPAGE TRUE
J 0
(-2925 4650);
DISPLAY 0.872340 (-2925 4650);
PAINT AQUA (-2925 4650);
DISPLAY INVISIBLE (-2925 4650);
FORCEPROP 1 LAST COMMENT_BODY TRUE
J 0
(-3295 4680);
DISPLAY 0.872340 (-3295 4680);
PAINT GREEN (-3295 4680);
DISPLAY INVISIBLE (-3295 4680);
FORCEPROP 2 LAST PATH I28
J 0
(-3075 4850);
DISPLAY 0.680851 (-3075 4850);
DISPLAY INVISIBLE (-3075 4850);
FORCEADD UNIVERSAL_GND..1
(-4000 4500);
FORCEPROP 3 LASTPIN (-4000 4550) SIG_NAME GND\g
J 0
(-3990 4560);
DISPLAY 0.659574 (-3990 4560);
PAINT MONO (-3990 4560);
DISPLAY INVISIBLE (-3990 4560);
FORCEPROP 2 LAST CDS_LIB pure_quanta_power
J 0
(-4000 4500);
DISPLAY INVISIBLE (-4000 4500);
FORCEPROP 1 LAST HDL_POWER GND
J 1
(-3975 4425);
DISPLAY 0.872340 (-3975 4425);
PAINT GREEN (-3975 4425);
DISPLAY INVISIBLE (-3975 4425);
FORCEPROP 1 LAST PATH I29
J 0
(-3925 4500);
DISPLAY 0.872340 (-3925 4500);
PAINT AQUA (-3925 4500);
DISPLAY INVISIBLE (-3925 4500);
FORCEADD Q_CAP..1
(-7725 6075);
FORCEPROP 1 LAST LOCATION C6009
J 0
(-7675 6175);
DISPLAY 0.510638 (-7675 6175);
FORCEPROP 0 LAST $SEC 1
J 0
(-7675 6200);
DISPLAY 0.680851 (-7675 6200);
PAINT MONO (-7675 6200);
DISPLAY INVISIBLE (-7675 6200);
FORCEPROP 0 LAST CDS_SEC 1
J 0
(-7675 6200);
DISPLAY 0.680851 (-7675 6200);
DISPLAY INVISIBLE (-7675 6200);
FORCEPROP 1 LASTPIN (-7725 6175) $PN 1
J 0
(-7715 6155);
DISPLAY 0.787234 (-7715 6155);
PAINT MONO (-7715 6155);
FORCEPROP 1 LASTPIN (-7725 5975) $PN 2
J 0
(-7715 5955);
DISPLAY 0.787234 (-7715 5955);
PAINT MONO (-7715 5955);
FORCEPROP 2 LAST ROOM PCIE REDRIVER BOM2
J 0
(-7675 6200);
DISPLAY 0.553191 (-7675 6200);
PAINT RED (-7675 6200);
FORCEPROP 1 LAST TOLERANCE 10%
J 0
(-7675 6025);
DISPLAY 0.510638 (-7675 6025);
FORCEPROP 1 LAST VALUE 1UF
J 0
(-7675 6125);
DISPLAY 0.510638 (-7675 6125);
FORCEPROP 1 LAST PACK_TYPE C0402
J 0
(-7675 5875);
DISPLAY 0.510638 (-7675 5875);
FORCEPROP 1 LAST MATERIAL X6S
J 0
(-7675 5975);
DISPLAY 0.510638 (-7675 5975);
FORCEPROP 1 LAST VOLTAGE 25V
J 0
(-7675 6075);
DISPLAY 0.510638 (-7675 6075);
FORCEPROP 2 LAST CDS_LIB pure_quanta
J 0
(-7725 6075);
DISPLAY INVISIBLE (-7725 6075);
FORCEPROP 1 LAST PATH I3
J 0
(-7675 6225);
DISPLAY 0.978723 (-7675 6225);
PAINT WHITE (-7675 6225);
DISPLAY INVISIBLE (-7675 6225);
FORCEPROP 1 LAST PART_NUMBER CH5104KEB02
J 0
(-7675 5925);
DISPLAY 0.510638 (-7675 5925);
DISPLAY INVISIBLE (-7675 5925);
FORCEADD UNIVERSAL_POWER..1
(-7000 3800);
FORCEPROP 3 LASTPIN (-7000 3750) SIG_NAME P3V3_AUX\g
J 0
(-6990 3760);
DISPLAY 0.659574 (-6990 3760);
PAINT MONO (-6990 3760);
DISPLAY INVISIBLE (-6990 3760);
FORCEPROP 1 LAST HDL_POWER P3V3_AUX
J 1
(-7000 3850);
DISPLAY 0.872340 (-7000 3850);
PAINT GREEN (-7000 3850);
FORCEPROP 2 LAST CDS_LIB pure_quanta_power
J 0
(-7000 3800);
DISPLAY INVISIBLE (-7000 3800);
FORCEPROP 1 LAST PATH I30
J 0
(-6950 3825);
DISPLAY 0.872340 (-6950 3825);
PAINT AQUA (-6950 3825);
DISPLAY INVISIBLE (-6950 3825);
FORCEADD Q_RES..2
(-7000 2850);
FORCEPROP 1 LAST LOCATION R6164
J 0
(-6955 2975);
DISPLAY 0.978723 (-6955 2975);
FORCEPROP 0 LAST $SEC 1
J 0
(-6950 3025);
DISPLAY 0.680851 (-6950 3025);
PAINT MONO (-6950 3025);
DISPLAY INVISIBLE (-6950 3025);
FORCEPROP 0 LAST CDS_SEC 1
J 0
(-6950 3025);
DISPLAY 0.680851 (-6950 3025);
DISPLAY INVISIBLE (-6950 3025);
FORCEPROP 1 LASTPIN (-7000 2950) $PN 1
J 0
(-6995 2912);
DISPLAY 0.787234 (-6995 2912);
PAINT MONO (-6995 2912);
FORCEPROP 1 LASTPIN (-7000 2750) $PN 2
J 0
(-6995 2760);
DISPLAY 0.787234 (-6995 2760);
PAINT MONO (-6995 2760);
FORCEPROP 2 LAST ROOM PCIE REDRIVER BOM2
J 0
(-6950 3025);
DISPLAY 0.446809 (-6950 3025);
PAINT RED (-6950 3025);
FORCEPROP 1 LAST TOLERANCE 1%
J 0
(-6955 2875);
DISPLAY 0.638298 (-6955 2875);
FORCEPROP 1 LAST VALUE 1K
J 0
(-6955 2925);
DISPLAY 0.638298 (-6955 2925);
FORCEPROP 1 LAST MATERIAL CHIP
J 0
(-6960 2775);
DISPLAY 0.638298 (-6960 2775);
FORCEPROP 1 LAST WATTAGE 1/16W
J 0
(-6960 2825);
DISPLAY 0.638298 (-6960 2825);
FORCEPROP 1 LAST PACK_TYPE 0402LF
J 0
(-6960 2675);
DISPLAY 0.638298 (-6960 2675);
FORCEPROP 2 LAST CDS_LIB pure_quanta
J 0
(-7000 2850);
DISPLAY INVISIBLE (-7000 2850);
FORCEPROP 1 LAST PATH I32
J 0
(-6950 3025);
DISPLAY 0.978723 (-6950 3025);
PAINT WHITE (-6950 3025);
DISPLAY INVISIBLE (-6950 3025);
FORCEPROP 1 LAST PART_NUMBER CS21002FB06
J 0
(-6960 2725);
DISPLAY 0.638298 (-6960 2725);
DISPLAY INVISIBLE (-6960 2725);
FORCEADD UNIVERSAL_GND..1
(-7000 2400);
FORCEPROP 3 LASTPIN (-7000 2450) SIG_NAME GND\g
J 0
(-6990 2460);
DISPLAY 0.659574 (-6990 2460);
PAINT MONO (-6990 2460);
DISPLAY INVISIBLE (-6990 2460);
FORCEPROP 2 LAST CDS_LIB pure_quanta_power
J 0
(-7000 2400);
DISPLAY INVISIBLE (-7000 2400);
FORCEPROP 1 LAST HDL_POWER GND
J 1
(-6975 2325);
DISPLAY 0.872340 (-6975 2325);
PAINT GREEN (-6975 2325);
DISPLAY INVISIBLE (-6975 2325);
FORCEPROP 1 LAST PATH I35
J 0
(-6925 2400);
DISPLAY 0.872340 (-6925 2400);
PAINT AQUA (-6925 2400);
DISPLAY INVISIBLE (-6925 2400);
FORCEADD UNIVERSAL_GND..1
(-6550 2400);
FORCEPROP 3 LASTPIN (-6550 2450) SIG_NAME GND\g
J 0
(-6540 2460);
DISPLAY 0.659574 (-6540 2460);
PAINT MONO (-6540 2460);
DISPLAY INVISIBLE (-6540 2460);
FORCEPROP 2 LAST CDS_LIB pure_quanta_power
J 0
(-6550 2400);
DISPLAY INVISIBLE (-6550 2400);
FORCEPROP 1 LAST HDL_POWER GND
J 1
(-6525 2325);
DISPLAY 0.872340 (-6525 2325);
PAINT GREEN (-6525 2325);
DISPLAY INVISIBLE (-6525 2325);
FORCEPROP 1 LAST PATH I36
J 0
(-6475 2400);
DISPLAY 0.872340 (-6475 2400);
PAINT AQUA (-6475 2400);
DISPLAY INVISIBLE (-6475 2400);
FORCEADD OFFPAGE..2
(-5675 3200);
FORCEPROP 2 LAST $XR0 112 
J 0
(-5486 3200);
DISPLAY 0.638298 (-5486 3200);
PAINT MONO (-5486 3200);
FORCEPROP 2 LAST CDS_LIB standard
J 0
(-5675 3200);
DISPLAY INVISIBLE (-5675 3200);
FORCEPROP 1 LAST OFFPAGE TRUE
J 0
(-5350 3075);
DISPLAY 0.872340 (-5350 3075);
PAINT AQUA (-5350 3075);
DISPLAY INVISIBLE (-5350 3075);
FORCEPROP 1 LAST COMMENT_BODY TRUE
J 0
(-5720 3105);
DISPLAY 0.872340 (-5720 3105);
PAINT GREEN (-5720 3105);
DISPLAY INVISIBLE (-5720 3105);
FORCEPROP 2 LAST PATH I37
J 0
(-5500 3275);
DISPLAY 0.680851 (-5500 3275);
DISPLAY INVISIBLE (-5500 3275);
FORCEADD OFFPAGE..2
(-5675 3125);
FORCEPROP 2 LAST $XR0 112 
J 0
(-5486 3125);
DISPLAY 0.638298 (-5486 3125);
PAINT MONO (-5486 3125);
FORCEPROP 2 LAST CDS_LIB standard
J 0
(-5675 3125);
DISPLAY INVISIBLE (-5675 3125);
FORCEPROP 1 LAST OFFPAGE TRUE
J 0
(-5350 3000);
DISPLAY 0.872340 (-5350 3000);
PAINT AQUA (-5350 3000);
DISPLAY INVISIBLE (-5350 3000);
FORCEPROP 1 LAST COMMENT_BODY TRUE
J 0
(-5720 3030);
DISPLAY 0.872340 (-5720 3030);
PAINT GREEN (-5720 3030);
DISPLAY INVISIBLE (-5720 3030);
FORCEPROP 2 LAST PATH I38
J 0
(-5500 3200);
DISPLAY 0.680851 (-5500 3200);
DISPLAY INVISIBLE (-5500 3200);
FORCEADD Q_RES..2
(-7000 3425);
FORCEPROP 1 LAST LOCATION R6163
J 0
(-6955 3550);
DISPLAY 0.638298 (-6955 3550);
FORCEPROP 0 LAST $SEC 1
J 0
(-6950 3600);
DISPLAY 0.680851 (-6950 3600);
PAINT MONO (-6950 3600);
DISPLAY INVISIBLE (-6950 3600);
FORCEPROP 0 LAST CDS_SEC 1
J 0
(-6950 3600);
DISPLAY 0.680851 (-6950 3600);
DISPLAY INVISIBLE (-6950 3600);
FORCEPROP 1 LASTPIN (-7000 3525) $PN 1
J 0
(-6995 3487);
DISPLAY 0.787234 (-6995 3487);
PAINT MONO (-6995 3487);
FORCEPROP 1 LASTPIN (-7000 3325) $PN 2
J 0
(-6995 3335);
DISPLAY 0.787234 (-6995 3335);
PAINT MONO (-6995 3335);
FORCEPROP 1 LAST VALUE 1K
J 0
(-6955 3500);
DISPLAY 0.638298 (-6955 3500);
FORCEPROP 1 LAST TOLERANCE 1%
J 0
(-6955 3450);
DISPLAY 0.638298 (-6955 3450);
FORCEPROP 1 LAST PACK_TYPE 0402LF
J 0
(-6960 3250);
DISPLAY 0.638298 (-6960 3250);
FORCEPROP 1 LAST MATERIAL EMPTY
J 0
(-6960 3350);
DISPLAY 0.638298 (-6960 3350);
FORCEPROP 1 LAST WATTAGE 1/16W
J 0
(-6960 3400);
DISPLAY 0.638298 (-6960 3400);
FORCEPROP 2 LAST ROOM PCIE REDRIVER BOM2
J 0
(-6950 3600);
DISPLAY 0.446809 (-6950 3600);
PAINT RED (-6950 3600);
FORCEPROP 2 LAST CDS_LIB pure_quanta
J 0
(-7000 3425);
DISPLAY INVISIBLE (-7000 3425);
FORCEPROP 1 LAST PATH I39
J 0
(-6950 3600);
DISPLAY 0.978723 (-6950 3600);
PAINT WHITE (-6950 3600);
DISPLAY INVISIBLE (-6950 3600);
FORCEPROP 1 LAST PART_NUMBER CS21002FB06
J 0
(-6960 3300);
DISPLAY 0.638298 (-6960 3300);
DISPLAY INVISIBLE (-6960 3300);
FORCEADD UNIVERSAL_GND..1
(-6675 5650);
FORCEPROP 3 LASTPIN (-6675 5700) SIG_NAME GND\g
J 0
(-6665 5710);
DISPLAY 0.659574 (-6665 5710);
PAINT MONO (-6665 5710);
DISPLAY INVISIBLE (-6665 5710);
FORCEPROP 2 LAST CDS_LIB pure_quanta_power
J 0
(-6675 5650);
DISPLAY INVISIBLE (-6675 5650);
FORCEPROP 1 LAST HDL_POWER GND
J 1
(-6650 5575);
DISPLAY 0.872340 (-6650 5575);
PAINT GREEN (-6650 5575);
DISPLAY INVISIBLE (-6650 5575);
FORCEPROP 1 LAST PATH I4
J 0
(-6600 5650);
DISPLAY 0.872340 (-6600 5650);
PAINT AQUA (-6600 5650);
DISPLAY INVISIBLE (-6600 5650);
FORCEADD Q_RES..2
(-6550 2850);
FORCEPROP 1 LAST LOCATION R6166
J 0
(-6505 2975);
DISPLAY 0.978723 (-6505 2975);
FORCEPROP 0 LAST $SEC 1
J 0
(-6500 3025);
DISPLAY 0.680851 (-6500 3025);
PAINT MONO (-6500 3025);
DISPLAY INVISIBLE (-6500 3025);
FORCEPROP 0 LAST CDS_SEC 1
J 0
(-6500 3025);
DISPLAY 0.680851 (-6500 3025);
DISPLAY INVISIBLE (-6500 3025);
FORCEPROP 1 LASTPIN (-6550 2950) $PN 1
J 0
(-6545 2912);
DISPLAY 0.787234 (-6545 2912);
PAINT MONO (-6545 2912);
FORCEPROP 1 LASTPIN (-6550 2750) $PN 2
J 0
(-6545 2760);
DISPLAY 0.787234 (-6545 2760);
PAINT MONO (-6545 2760);
FORCEPROP 1 LAST PACK_TYPE 0402LF
J 0
(-6510 2675);
DISPLAY 0.638298 (-6510 2675);
FORCEPROP 1 LAST MATERIAL EMPTY
J 0
(-6510 2775);
DISPLAY 0.638298 (-6510 2775);
FORCEPROP 1 LAST VALUE 1K
J 0
(-6505 2925);
DISPLAY 0.638298 (-6505 2925);
FORCEPROP 1 LAST TOLERANCE 1%
J 0
(-6505 2875);
DISPLAY 0.638298 (-6505 2875);
FORCEPROP 1 LAST WATTAGE 1/16W
J 0
(-6510 2825);
DISPLAY 0.638298 (-6510 2825);
FORCEPROP 2 LAST ROOM PCIE REDRIVER BOM2
J 0
(-6500 3025);
DISPLAY 0.446809 (-6500 3025);
PAINT RED (-6500 3025);
FORCEPROP 2 LAST CDS_LIB pure_quanta
J 0
(-6550 2850);
DISPLAY INVISIBLE (-6550 2850);
FORCEPROP 1 LAST PATH I40
J 0
(-6500 3025);
DISPLAY 0.978723 (-6500 3025);
PAINT WHITE (-6500 3025);
DISPLAY INVISIBLE (-6500 3025);
FORCEPROP 1 LAST PART_NUMBER CS21002FB06
J 0
(-6510 2725);
DISPLAY 0.638298 (-6510 2725);
DISPLAY INVISIBLE (-6510 2725);
FORCEADD Q_RES..2
(-6550 3425);
FORCEPROP 1 LAST LOCATION R6165
J 0
(-6505 3550);
DISPLAY 0.978723 (-6505 3550);
FORCEPROP 0 LAST $SEC 1
J 0
(-6500 3600);
DISPLAY 0.680851 (-6500 3600);
PAINT MONO (-6500 3600);
DISPLAY INVISIBLE (-6500 3600);
FORCEPROP 0 LAST CDS_SEC 1
J 0
(-6500 3600);
DISPLAY 0.680851 (-6500 3600);
DISPLAY INVISIBLE (-6500 3600);
FORCEPROP 1 LASTPIN (-6550 3525) $PN 1
J 0
(-6545 3487);
DISPLAY 0.787234 (-6545 3487);
PAINT MONO (-6545 3487);
FORCEPROP 1 LASTPIN (-6550 3325) $PN 2
J 0
(-6545 3335);
DISPLAY 0.787234 (-6545 3335);
PAINT MONO (-6545 3335);
FORCEPROP 2 LAST ROOM PCIE REDRIVER BOM2
J 0
(-6500 3600);
DISPLAY 0.446809 (-6500 3600);
PAINT RED (-6500 3600);
FORCEPROP 1 LAST WATTAGE 1/16W
J 0
(-6510 3400);
DISPLAY 0.638298 (-6510 3400);
FORCEPROP 1 LAST MATERIAL EMPTY
J 0
(-6510 3350);
DISPLAY 0.638298 (-6510 3350);
FORCEPROP 1 LAST TOLERANCE 1%
J 0
(-6505 3450);
DISPLAY 0.638298 (-6505 3450);
FORCEPROP 1 LAST VALUE 1K
J 0
(-6505 3500);
DISPLAY 0.638298 (-6505 3500);
FORCEPROP 1 LAST PACK_TYPE 0402LF
J 0
(-6510 3250);
DISPLAY 0.638298 (-6510 3250);
FORCEPROP 2 LAST CDS_LIB pure_quanta
J 0
(-6550 3425);
DISPLAY INVISIBLE (-6550 3425);
FORCEPROP 1 LAST PATH I41
J 0
(-6500 3600);
DISPLAY 0.978723 (-6500 3600);
PAINT WHITE (-6500 3600);
DISPLAY INVISIBLE (-6500 3600);
FORCEPROP 1 LAST PART_NUMBER CS21002FB06
J 0
(-6510 3300);
DISPLAY 0.638298 (-6510 3300);
DISPLAY INVISIBLE (-6510 3300);
FORCEADD OFFPAGE..2
(-3750 3200);
FORCEPROP 2 LAST $XR0 112 
J 0
(-3561 3200);
DISPLAY 0.638298 (-3561 3200);
PAINT MONO (-3561 3200);
FORCEPROP 2 LAST CDS_LIB standard
J 0
(-3750 3200);
DISPLAY INVISIBLE (-3750 3200);
FORCEPROP 1 LAST OFFPAGE TRUE
J 0
(-3425 3075);
DISPLAY 0.872340 (-3425 3075);
PAINT AQUA (-3425 3075);
DISPLAY INVISIBLE (-3425 3075);
FORCEPROP 1 LAST COMMENT_BODY TRUE
J 0
(-3795 3105);
DISPLAY 0.872340 (-3795 3105);
PAINT GREEN (-3795 3105);
DISPLAY INVISIBLE (-3795 3105);
FORCEPROP 2 LAST PATH I42
J 0
(-3575 3275);
DISPLAY 0.680851 (-3575 3275);
DISPLAY INVISIBLE (-3575 3275);
FORCEADD OFFPAGE..2
(-3750 3125);
FORCEPROP 2 LAST $XR0 112 
J 0
(-3561 3125);
DISPLAY 0.638298 (-3561 3125);
PAINT MONO (-3561 3125);
FORCEPROP 2 LAST CDS_LIB standard
J 0
(-3750 3125);
DISPLAY INVISIBLE (-3750 3125);
FORCEPROP 1 LAST OFFPAGE TRUE
J 0
(-3425 3000);
DISPLAY 0.872340 (-3425 3000);
PAINT AQUA (-3425 3000);
DISPLAY INVISIBLE (-3425 3000);
FORCEPROP 1 LAST COMMENT_BODY TRUE
J 0
(-3795 3030);
DISPLAY 0.872340 (-3795 3030);
PAINT GREEN (-3795 3030);
DISPLAY INVISIBLE (-3795 3030);
FORCEPROP 2 LAST PATH I43
J 0
(-3575 3200);
DISPLAY 0.680851 (-3575 3200);
DISPLAY INVISIBLE (-3575 3200);
FORCEADD Q_RES..2
(-4625 3425);
FORCEPROP 1 LAST LOCATION R6173
J 0
(-4580 3550);
DISPLAY 0.978723 (-4580 3550);
FORCEPROP 0 LAST $SEC 1
J 0
(-4575 3600);
DISPLAY 0.680851 (-4575 3600);
PAINT MONO (-4575 3600);
DISPLAY INVISIBLE (-4575 3600);
FORCEPROP 0 LAST CDS_SEC 1
J 0
(-4575 3600);
DISPLAY 0.680851 (-4575 3600);
DISPLAY INVISIBLE (-4575 3600);
FORCEPROP 1 LASTPIN (-4625 3525) $PN 1
J 0
(-4620 3487);
DISPLAY 0.787234 (-4620 3487);
PAINT MONO (-4620 3487);
FORCEPROP 1 LASTPIN (-4625 3325) $PN 2
J 0
(-4620 3335);
DISPLAY 0.787234 (-4620 3335);
PAINT MONO (-4620 3335);
FORCEPROP 1 LAST WATTAGE 1/16W
J 0
(-4585 3400);
DISPLAY 0.638298 (-4585 3400);
FORCEPROP 1 LAST MATERIAL EMPTY
J 0
(-4585 3350);
DISPLAY 0.638298 (-4585 3350);
FORCEPROP 1 LAST PACK_TYPE 0402LF
J 0
(-4585 3250);
DISPLAY 0.638298 (-4585 3250);
FORCEPROP 1 LAST TOLERANCE 1%
J 0
(-4580 3450);
DISPLAY 0.638298 (-4580 3450);
FORCEPROP 1 LAST VALUE 1K
J 0
(-4580 3500);
DISPLAY 0.638298 (-4580 3500);
FORCEPROP 2 LAST ROOM PCIE REDRIVER BOM2
J 0
(-4575 3600);
DISPLAY 0.446809 (-4575 3600);
PAINT RED (-4575 3600);
FORCEPROP 2 LAST CDS_LIB pure_quanta
J 0
(-4625 3425);
DISPLAY INVISIBLE (-4625 3425);
FORCEPROP 1 LAST PATH I44
J 0
(-4575 3600);
DISPLAY 0.978723 (-4575 3600);
PAINT WHITE (-4575 3600);
DISPLAY INVISIBLE (-4575 3600);
FORCEPROP 1 LAST PART_NUMBER CS21002FB06
J 0
(-4585 3300);
DISPLAY 0.638298 (-4585 3300);
DISPLAY INVISIBLE (-4585 3300);
FORCEADD Q_RES..2
(-4625 2850);
FORCEPROP 1 LAST LOCATION R6174
J 0
(-4580 2975);
DISPLAY 0.978723 (-4580 2975);
FORCEPROP 0 LAST $SEC 1
J 0
(-4575 3025);
DISPLAY 0.680851 (-4575 3025);
PAINT MONO (-4575 3025);
DISPLAY INVISIBLE (-4575 3025);
FORCEPROP 0 LAST CDS_SEC 1
J 0
(-4575 3025);
DISPLAY 0.680851 (-4575 3025);
DISPLAY INVISIBLE (-4575 3025);
FORCEPROP 1 LASTPIN (-4625 2950) $PN 1
J 0
(-4620 2912);
DISPLAY 0.787234 (-4620 2912);
PAINT MONO (-4620 2912);
FORCEPROP 1 LASTPIN (-4625 2750) $PN 2
J 0
(-4620 2760);
DISPLAY 0.787234 (-4620 2760);
PAINT MONO (-4620 2760);
FORCEPROP 1 LAST PACK_TYPE 0402LF
J 0
(-4585 2675);
DISPLAY 0.638298 (-4585 2675);
FORCEPROP 1 LAST TOLERANCE 1%
J 0
(-4580 2875);
DISPLAY 0.638298 (-4580 2875);
FORCEPROP 1 LAST WATTAGE 1/16W
J 0
(-4585 2825);
DISPLAY 0.638298 (-4585 2825);
FORCEPROP 1 LAST MATERIAL EMPTY
J 0
(-4585 2775);
DISPLAY 0.638298 (-4585 2775);
FORCEPROP 1 LAST VALUE 1K
J 0
(-4580 2925);
DISPLAY 0.638298 (-4580 2925);
FORCEPROP 2 LAST ROOM PCIE REDRIVER BOM2
J 0
(-4575 3025);
DISPLAY 0.553191 (-4575 3025);
PAINT RED (-4575 3025);
FORCEPROP 2 LAST CDS_LIB pure_quanta
J 0
(-4625 2850);
DISPLAY INVISIBLE (-4625 2850);
FORCEPROP 1 LAST PATH I45
J 0
(-4575 3025);
DISPLAY 0.978723 (-4575 3025);
PAINT WHITE (-4575 3025);
DISPLAY INVISIBLE (-4575 3025);
FORCEPROP 1 LAST PART_NUMBER CS21002FB06
J 0
(-4585 2725);
DISPLAY 0.638298 (-4585 2725);
DISPLAY INVISIBLE (-4585 2725);
FORCEADD UNIVERSAL_GND..1
(-4625 2400);
FORCEPROP 3 LASTPIN (-4625 2450) SIG_NAME GND\g
J 0
(-4615 2460);
DISPLAY 0.659574 (-4615 2460);
PAINT MONO (-4615 2460);
DISPLAY INVISIBLE (-4615 2460);
FORCEPROP 2 LAST CDS_LIB pure_quanta_power
J 0
(-4625 2400);
DISPLAY INVISIBLE (-4625 2400);
FORCEPROP 1 LAST HDL_POWER GND
J 1
(-4600 2325);
DISPLAY 0.872340 (-4600 2325);
PAINT GREEN (-4600 2325);
DISPLAY INVISIBLE (-4600 2325);
FORCEPROP 1 LAST PATH I46
J 0
(-4550 2400);
DISPLAY 0.872340 (-4550 2400);
PAINT AQUA (-4550 2400);
DISPLAY INVISIBLE (-4550 2400);
FORCEADD UNIVERSAL_POWER..1
(-5075 3800);
FORCEPROP 3 LASTPIN (-5075 3750) SIG_NAME P3V3_AUX\g
J 0
(-5065 3760);
DISPLAY 0.659574 (-5065 3760);
PAINT MONO (-5065 3760);
DISPLAY INVISIBLE (-5065 3760);
FORCEPROP 1 LAST HDL_POWER P3V3_AUX
J 1
(-5075 3850);
DISPLAY 0.872340 (-5075 3850);
PAINT GREEN (-5075 3850);
FORCEPROP 2 LAST CDS_LIB pure_quanta_power
J 0
(-5075 3800);
DISPLAY INVISIBLE (-5075 3800);
FORCEPROP 1 LAST PATH I47
J 0
(-5025 3825);
DISPLAY 0.872340 (-5025 3825);
PAINT AQUA (-5025 3825);
DISPLAY INVISIBLE (-5025 3825);
FORCEADD Q_RES..2
(-5075 3425);
FORCEPROP 1 LAST LOCATION R6171
J 0
(-5030 3550);
DISPLAY 0.978723 (-5030 3550);
FORCEPROP 0 LAST $SEC 1
J 0
(-5025 3600);
DISPLAY 0.680851 (-5025 3600);
PAINT MONO (-5025 3600);
DISPLAY INVISIBLE (-5025 3600);
FORCEPROP 0 LAST CDS_SEC 1
J 0
(-5025 3600);
DISPLAY 0.680851 (-5025 3600);
DISPLAY INVISIBLE (-5025 3600);
FORCEPROP 1 LASTPIN (-5075 3525) $PN 1
J 0
(-5070 3487);
DISPLAY 0.787234 (-5070 3487);
PAINT MONO (-5070 3487);
FORCEPROP 1 LASTPIN (-5075 3325) $PN 2
J 0
(-5070 3335);
DISPLAY 0.787234 (-5070 3335);
PAINT MONO (-5070 3335);
FORCEPROP 2 LAST ROOM PCIE REDRIVER BOM2
J 0
(-5025 3600);
DISPLAY 0.446809 (-5025 3600);
PAINT RED (-5025 3600);
FORCEPROP 1 LAST PACK_TYPE 0402LF
J 0
(-5035 3250);
DISPLAY 0.638298 (-5035 3250);
FORCEPROP 1 LAST WATTAGE 1/16W
J 0
(-5035 3400);
DISPLAY 0.638298 (-5035 3400);
FORCEPROP 1 LAST TOLERANCE 1%
J 0
(-5030 3450);
DISPLAY 0.638298 (-5030 3450);
FORCEPROP 1 LAST VALUE 1K
J 0
(-5030 3500);
DISPLAY 0.638298 (-5030 3500);
FORCEPROP 1 LAST MATERIAL EMPTY
J 0
(-5035 3350);
DISPLAY 0.638298 (-5035 3350);
FORCEPROP 2 LAST CDS_LIB pure_quanta
J 0
(-5075 3425);
DISPLAY INVISIBLE (-5075 3425);
FORCEPROP 1 LAST PATH I48
J 0
(-5025 3600);
DISPLAY 0.978723 (-5025 3600);
PAINT WHITE (-5025 3600);
DISPLAY INVISIBLE (-5025 3600);
FORCEPROP 1 LAST PART_NUMBER CS21002FB06
J 0
(-5035 3300);
DISPLAY 0.638298 (-5035 3300);
DISPLAY INVISIBLE (-5035 3300);
FORCEADD Q_RES..2
(-5075 2850);
FORCEPROP 1 LAST LOCATION R6172
J 0
(-5030 2975);
DISPLAY 0.978723 (-5030 2975);
FORCEPROP 0 LAST $SEC 1
J 0
(-5025 3025);
DISPLAY 0.680851 (-5025 3025);
PAINT MONO (-5025 3025);
DISPLAY INVISIBLE (-5025 3025);
FORCEPROP 0 LAST CDS_SEC 1
J 0
(-5025 3025);
DISPLAY 0.680851 (-5025 3025);
DISPLAY INVISIBLE (-5025 3025);
FORCEPROP 1 LASTPIN (-5075 2950) $PN 1
J 0
(-5070 2912);
DISPLAY 0.787234 (-5070 2912);
PAINT MONO (-5070 2912);
FORCEPROP 1 LASTPIN (-5075 2750) $PN 2
J 0
(-5070 2760);
DISPLAY 0.787234 (-5070 2760);
PAINT MONO (-5070 2760);
FORCEPROP 2 LAST ROOM PCIE REDRIVER BOM2
J 0
(-5025 3025);
DISPLAY 0.446809 (-5025 3025);
PAINT RED (-5025 3025);
FORCEPROP 1 LAST WATTAGE 1/16W
J 0
(-5035 2825);
DISPLAY 0.638298 (-5035 2825);
FORCEPROP 1 LAST VALUE 1K
J 0
(-5030 2925);
DISPLAY 0.638298 (-5030 2925);
FORCEPROP 1 LAST PACK_TYPE 0402LF
J 0
(-5035 2675);
DISPLAY 0.638298 (-5035 2675);
FORCEPROP 1 LAST MATERIAL CHIP
J 0
(-5035 2775);
DISPLAY 0.638298 (-5035 2775);
FORCEPROP 1 LAST TOLERANCE 1%
J 0
(-5030 2875);
DISPLAY 0.638298 (-5030 2875);
FORCEPROP 2 LAST CDS_LIB pure_quanta
J 0
(-5075 2850);
DISPLAY INVISIBLE (-5075 2850);
FORCEPROP 1 LAST PATH I49
J 0
(-5025 3025);
DISPLAY 0.978723 (-5025 3025);
PAINT WHITE (-5025 3025);
DISPLAY INVISIBLE (-5025 3025);
FORCEPROP 1 LAST PART_NUMBER CS21002FB06
J 0
(-5035 2725);
DISPLAY 0.638298 (-5035 2725);
DISPLAY INVISIBLE (-5035 2725);
FORCEADD Q_CAP..1
(-7150 6075);
FORCEPROP 1 LAST LOCATION C6010
J 0
(-7100 6175);
DISPLAY 0.510638 (-7100 6175);
FORCEPROP 0 LAST $SEC 1
J 0
(-7100 6200);
DISPLAY 0.680851 (-7100 6200);
PAINT MONO (-7100 6200);
DISPLAY INVISIBLE (-7100 6200);
FORCEPROP 0 LAST CDS_SEC 1
J 0
(-7100 6200);
DISPLAY 0.680851 (-7100 6200);
DISPLAY INVISIBLE (-7100 6200);
FORCEPROP 1 LASTPIN (-7150 6175) $PN 1
J 0
(-7140 6155);
DISPLAY 0.787234 (-7140 6155);
PAINT MONO (-7140 6155);
FORCEPROP 1 LASTPIN (-7150 5975) $PN 2
J 0
(-7140 5955);
DISPLAY 0.787234 (-7140 5955);
PAINT MONO (-7140 5955);
FORCEPROP 1 LAST TOLERANCE 10%
J 0
(-7100 6025);
DISPLAY 0.510638 (-7100 6025);
FORCEPROP 2 LAST ROOM PCIE REDRIVER BOM2
J 0
(-7100 6200);
DISPLAY 0.553191 (-7100 6200);
PAINT RED (-7100 6200);
FORCEPROP 1 LAST VALUE 10UF
J 0
(-7100 6125);
DISPLAY 0.510638 (-7100 6125);
FORCEPROP 1 LAST PACK_TYPE C0805
J 0
(-7100 5875);
DISPLAY 0.510638 (-7100 5875);
FORCEPROP 1 LAST MATERIAL X6S
J 0
(-7100 5975);
DISPLAY 0.510638 (-7100 5975);
FORCEPROP 1 LAST VOLTAGE 16V
J 0
(-7100 6075);
DISPLAY 0.510638 (-7100 6075);
FORCEPROP 2 LAST CDS_LIB pure_quanta
J 0
(-7150 6075);
DISPLAY INVISIBLE (-7150 6075);
FORCEPROP 1 LAST PATH I5
J 0
(-7100 6225);
DISPLAY 0.978723 (-7100 6225);
PAINT WHITE (-7100 6225);
DISPLAY INVISIBLE (-7100 6225);
FORCEPROP 1 LAST PART_NUMBER CH6103KEA00
J 0
(-7100 5925);
DISPLAY 0.510638 (-7100 5925);
DISPLAY INVISIBLE (-7100 5925);
FORCEADD UNIVERSAL_GND..1
(-5075 2400);
FORCEPROP 3 LASTPIN (-5075 2450) SIG_NAME GND\g
J 0
(-5065 2460);
DISPLAY 0.659574 (-5065 2460);
PAINT MONO (-5065 2460);
DISPLAY INVISIBLE (-5065 2460);
FORCEPROP 2 LAST CDS_LIB pure_quanta_power
J 0
(-5075 2400);
DISPLAY INVISIBLE (-5075 2400);
FORCEPROP 1 LAST HDL_POWER GND
J 1
(-5050 2325);
DISPLAY 0.872340 (-5050 2325);
PAINT GREEN (-5050 2325);
DISPLAY INVISIBLE (-5050 2325);
FORCEPROP 1 LAST PATH I50
J 0
(-5000 2400);
DISPLAY 0.872340 (-5000 2400);
PAINT AQUA (-5000 2400);
DISPLAY INVISIBLE (-5000 2400);
FORCEADD OFFPAGE..2
(-5650 1500);
FORCEPROP 2 LAST $XR0 112 
J 0
(-5461 1500);
DISPLAY 0.638298 (-5461 1500);
PAINT MONO (-5461 1500);
FORCEPROP 2 LAST CDS_LIB standard
J 0
(-5650 1500);
DISPLAY INVISIBLE (-5650 1500);
FORCEPROP 1 LAST OFFPAGE TRUE
J 0
(-5325 1375);
DISPLAY 0.872340 (-5325 1375);
PAINT AQUA (-5325 1375);
DISPLAY INVISIBLE (-5325 1375);
FORCEPROP 1 LAST COMMENT_BODY TRUE
J 0
(-5695 1405);
DISPLAY 0.872340 (-5695 1405);
PAINT GREEN (-5695 1405);
DISPLAY INVISIBLE (-5695 1405);
FORCEPROP 2 LAST PATH I51
J 0
(-5475 1575);
DISPLAY 0.680851 (-5475 1575);
DISPLAY INVISIBLE (-5475 1575);
FORCEADD OFFPAGE..2
(-5650 1425);
FORCEPROP 2 LAST $XR0 112 
J 0
(-5461 1425);
DISPLAY 0.638298 (-5461 1425);
PAINT MONO (-5461 1425);
FORCEPROP 2 LAST CDS_LIB standard
J 0
(-5650 1425);
DISPLAY INVISIBLE (-5650 1425);
FORCEPROP 1 LAST OFFPAGE TRUE
J 0
(-5325 1300);
DISPLAY 0.872340 (-5325 1300);
PAINT AQUA (-5325 1300);
DISPLAY INVISIBLE (-5325 1300);
FORCEPROP 1 LAST COMMENT_BODY TRUE
J 0
(-5695 1330);
DISPLAY 0.872340 (-5695 1330);
PAINT GREEN (-5695 1330);
DISPLAY INVISIBLE (-5695 1330);
FORCEPROP 2 LAST PATH I52
J 0
(-5475 1500);
DISPLAY 0.680851 (-5475 1500);
DISPLAY INVISIBLE (-5475 1500);
FORCEADD Q_RES..2
(-6525 1725);
FORCEPROP 1 LAST LOCATION R6169
J 0
(-6480 1850);
DISPLAY 0.978723 (-6480 1850);
FORCEPROP 0 LAST $SEC 1
J 0
(-6475 1900);
DISPLAY 0.680851 (-6475 1900);
PAINT MONO (-6475 1900);
DISPLAY INVISIBLE (-6475 1900);
FORCEPROP 0 LAST CDS_SEC 1
J 0
(-6475 1900);
DISPLAY 0.680851 (-6475 1900);
DISPLAY INVISIBLE (-6475 1900);
FORCEPROP 1 LASTPIN (-6525 1825) $PN 1
J 0
(-6520 1787);
DISPLAY 0.787234 (-6520 1787);
PAINT MONO (-6520 1787);
FORCEPROP 1 LASTPIN (-6525 1625) $PN 2
J 0
(-6520 1635);
DISPLAY 0.787234 (-6520 1635);
PAINT MONO (-6520 1635);
FORCEPROP 1 LAST PACK_TYPE 0402LF
J 0
(-6485 1550);
DISPLAY 0.638298 (-6485 1550);
FORCEPROP 1 LAST MATERIAL EMPTY
J 0
(-6485 1650);
DISPLAY 0.638298 (-6485 1650);
FORCEPROP 1 LAST WATTAGE 1/16W
J 0
(-6485 1700);
DISPLAY 0.638298 (-6485 1700);
FORCEPROP 1 LAST TOLERANCE 1%
J 0
(-6480 1750);
DISPLAY 0.638298 (-6480 1750);
FORCEPROP 1 LAST VALUE 1K
J 0
(-6480 1800);
DISPLAY 0.638298 (-6480 1800);
FORCEPROP 2 LAST ROOM PCIE REDRIVER BOM2
J 0
(-6475 1900);
DISPLAY 0.553191 (-6475 1900);
PAINT RED (-6475 1900);
FORCEPROP 2 LAST CDS_LIB pure_quanta
J 0
(-6525 1725);
DISPLAY INVISIBLE (-6525 1725);
FORCEPROP 1 LAST PATH I53
J 0
(-6475 1900);
DISPLAY 0.978723 (-6475 1900);
PAINT WHITE (-6475 1900);
DISPLAY INVISIBLE (-6475 1900);
FORCEPROP 1 LAST PART_NUMBER CS21002FB06
J 0
(-6485 1600);
DISPLAY 0.638298 (-6485 1600);
DISPLAY INVISIBLE (-6485 1600);
FORCEADD UNIVERSAL_GND..1
(-6525 700);
FORCEPROP 3 LASTPIN (-6525 750) SIG_NAME GND\g
J 0
(-6515 760);
DISPLAY 0.659574 (-6515 760);
PAINT MONO (-6515 760);
DISPLAY INVISIBLE (-6515 760);
FORCEPROP 2 LAST CDS_LIB pure_quanta_power
J 0
(-6525 700);
DISPLAY INVISIBLE (-6525 700);
FORCEPROP 1 LAST HDL_POWER GND
J 1
(-6500 625);
DISPLAY 0.872340 (-6500 625);
PAINT GREEN (-6500 625);
DISPLAY INVISIBLE (-6500 625);
FORCEPROP 1 LAST PATH I55
J 0
(-6450 700);
DISPLAY 0.872340 (-6450 700);
PAINT AQUA (-6450 700);
DISPLAY INVISIBLE (-6450 700);
FORCEADD UNIVERSAL_POWER..1
(-6975 2100);
FORCEPROP 3 LASTPIN (-6975 2050) SIG_NAME P3V3_AUX\g
J 0
(-6965 2060);
DISPLAY 0.659574 (-6965 2060);
PAINT MONO (-6965 2060);
DISPLAY INVISIBLE (-6965 2060);
FORCEPROP 1 LAST HDL_POWER P3V3_AUX
J 1
(-6975 2150);
DISPLAY 0.872340 (-6975 2150);
PAINT GREEN (-6975 2150);
FORCEPROP 2 LAST CDS_LIB pure_quanta_power
J 0
(-6975 2100);
DISPLAY INVISIBLE (-6975 2100);
FORCEPROP 1 LAST PATH I56
J 0
(-6925 2125);
DISPLAY 0.872340 (-6925 2125);
PAINT AQUA (-6925 2125);
DISPLAY INVISIBLE (-6925 2125);
FORCEADD Q_RES..2
(-6975 1725);
FORCEPROP 1 LAST LOCATION R6167
J 0
(-6930 1850);
DISPLAY 0.978723 (-6930 1850);
FORCEPROP 0 LAST $SEC 1
J 0
(-6925 1900);
DISPLAY 0.680851 (-6925 1900);
PAINT MONO (-6925 1900);
DISPLAY INVISIBLE (-6925 1900);
FORCEPROP 0 LAST CDS_SEC 1
J 0
(-6925 1900);
DISPLAY 0.680851 (-6925 1900);
DISPLAY INVISIBLE (-6925 1900);
FORCEPROP 1 LASTPIN (-6975 1825) $PN 1
J 0
(-6970 1787);
DISPLAY 0.787234 (-6970 1787);
PAINT MONO (-6970 1787);
FORCEPROP 1 LASTPIN (-6975 1625) $PN 2
J 0
(-6970 1635);
DISPLAY 0.787234 (-6970 1635);
PAINT MONO (-6970 1635);
FORCEPROP 1 LAST VALUE 1K
J 0
(-6930 1800);
DISPLAY 0.638298 (-6930 1800);
FORCEPROP 1 LAST TOLERANCE 1%
J 0
(-6930 1750);
DISPLAY 0.638298 (-6930 1750);
FORCEPROP 1 LAST WATTAGE 1/16W
J 0
(-6935 1700);
DISPLAY 0.638298 (-6935 1700);
FORCEPROP 1 LAST MATERIAL EMPTY
J 0
(-6935 1650);
DISPLAY 0.638298 (-6935 1650);
FORCEPROP 1 LAST PACK_TYPE 0402LF
J 0
(-6935 1550);
DISPLAY 0.638298 (-6935 1550);
FORCEPROP 2 LAST ROOM PCIE REDRIVER BOM2
J 0
(-6925 1900);
DISPLAY 0.446809 (-6925 1900);
PAINT RED (-6925 1900);
FORCEPROP 2 LAST CDS_LIB pure_quanta
J 0
(-6975 1725);
DISPLAY INVISIBLE (-6975 1725);
FORCEPROP 1 LAST PATH I57
J 0
(-6925 1900);
DISPLAY 0.978723 (-6925 1900);
PAINT WHITE (-6925 1900);
DISPLAY INVISIBLE (-6925 1900);
FORCEPROP 1 LAST PART_NUMBER CS21002FB06
J 0
(-6935 1600);
DISPLAY 0.638298 (-6935 1600);
DISPLAY INVISIBLE (-6935 1600);
FORCEADD Q_RES..2
(-6975 1150);
FORCEPROP 1 LAST LOCATION R6168
J 0
(-6930 1275);
DISPLAY 0.978723 (-6930 1275);
FORCEPROP 0 LAST $SEC 1
J 0
(-6925 1325);
DISPLAY 0.680851 (-6925 1325);
PAINT MONO (-6925 1325);
DISPLAY INVISIBLE (-6925 1325);
FORCEPROP 0 LAST CDS_SEC 1
J 0
(-6925 1325);
DISPLAY 0.680851 (-6925 1325);
DISPLAY INVISIBLE (-6925 1325);
FORCEPROP 1 LASTPIN (-6975 1250) $PN 1
J 0
(-6970 1212);
DISPLAY 0.787234 (-6970 1212);
PAINT MONO (-6970 1212);
FORCEPROP 1 LASTPIN (-6975 1050) $PN 2
J 0
(-6970 1060);
DISPLAY 0.787234 (-6970 1060);
PAINT MONO (-6970 1060);
FORCEPROP 2 LAST ROOM PCIE REDRIVER BOM2
J 0
(-6925 1325);
DISPLAY 0.446809 (-6925 1325);
PAINT RED (-6925 1325);
FORCEPROP 1 LAST PACK_TYPE 0402LF
J 0
(-6935 975);
DISPLAY 0.638298 (-6935 975);
FORCEPROP 1 LAST MATERIAL CHIP
J 0
(-6935 1075);
DISPLAY 0.638298 (-6935 1075);
FORCEPROP 1 LAST WATTAGE 1/16W
J 0
(-6935 1125);
DISPLAY 0.638298 (-6935 1125);
FORCEPROP 1 LAST VALUE 1K
J 0
(-6930 1225);
DISPLAY 0.638298 (-6930 1225);
FORCEPROP 1 LAST TOLERANCE 1%
J 0
(-6930 1175);
DISPLAY 0.638298 (-6930 1175);
FORCEPROP 2 LAST CDS_LIB pure_quanta
J 0
(-6975 1150);
DISPLAY INVISIBLE (-6975 1150);
FORCEPROP 1 LAST PATH I58
J 0
(-6925 1325);
DISPLAY 0.978723 (-6925 1325);
PAINT WHITE (-6925 1325);
DISPLAY INVISIBLE (-6925 1325);
FORCEPROP 1 LAST PART_NUMBER CS21002FB06
J 0
(-6935 1025);
DISPLAY 0.638298 (-6935 1025);
DISPLAY INVISIBLE (-6935 1025);
FORCEADD UNIVERSAL_GND..1
(-6975 700);
FORCEPROP 3 LASTPIN (-6975 750) SIG_NAME GND\g
J 0
(-6965 760);
DISPLAY 0.659574 (-6965 760);
PAINT MONO (-6965 760);
DISPLAY INVISIBLE (-6965 760);
FORCEPROP 2 LAST CDS_LIB pure_quanta_power
J 0
(-6975 700);
DISPLAY INVISIBLE (-6975 700);
FORCEPROP 1 LAST HDL_POWER GND
J 1
(-6950 625);
DISPLAY 0.872340 (-6950 625);
PAINT GREEN (-6950 625);
DISPLAY INVISIBLE (-6950 625);
FORCEPROP 1 LAST PATH I59
J 0
(-6900 700);
DISPLAY 0.872340 (-6900 700);
PAINT AQUA (-6900 700);
DISPLAY INVISIBLE (-6900 700);
FORCEADD Q_CAP..1
(-6575 6025);
FORCEPROP 1 LAST LOCATION C6011
J 0
(-6525 6125);
DISPLAY 0.638298 (-6525 6125);
FORCEPROP 0 LAST $SEC 1
J 0
(-6525 6175);
DISPLAY 0.680851 (-6525 6175);
PAINT MONO (-6525 6175);
DISPLAY INVISIBLE (-6525 6175);
FORCEPROP 0 LAST CDS_SEC 1
J 0
(-6525 6175);
DISPLAY 0.680851 (-6525 6175);
DISPLAY INVISIBLE (-6525 6175);
FORCEPROP 1 LASTPIN (-6575 6125) $PN 1
J 0
(-6565 6105);
DISPLAY 0.787234 (-6565 6105);
PAINT MONO (-6565 6105);
FORCEPROP 1 LASTPIN (-6575 5925) $PN 2
J 0
(-6565 5905);
DISPLAY 0.787234 (-6565 5905);
PAINT MONO (-6565 5905);
FORCEPROP 1 LAST PACK_TYPE 0402
J 0
(-6525 5875);
DISPLAY 0.510638 (-6525 5875);
FORCEPROP 1 LAST TOLERANCE 10%
J 0
(-6525 5975);
DISPLAY 0.510638 (-6525 5975);
FORCEPROP 1 LAST MATERIAL X7R
J 0
(-6525 5925);
DISPLAY 0.510638 (-6525 5925);
FORCEPROP 1 LAST VOLTAGE 25V
J 0
(-6525 6025);
DISPLAY 0.510638 (-6525 6025);
FORCEPROP 1 LAST VALUE 0.1UF
J 0
(-6525 6075);
DISPLAY 0.510638 (-6525 6075);
FORCEPROP 2 LAST ROOM PCIE REDRIVER BOM2
J 0
(-6525 6175);
DISPLAY 0.553191 (-6525 6175);
PAINT RED (-6525 6175);
FORCEPROP 2 LAST CDS_LIB pure_quanta
J 0
(-6575 6025);
DISPLAY INVISIBLE (-6575 6025);
FORCEPROP 1 LAST PATH I6
J 0
(-6525 6175);
DISPLAY 0.978723 (-6525 6175);
PAINT WHITE (-6525 6175);
DISPLAY INVISIBLE (-6525 6175);
FORCEPROP 1 LAST PART_NUMBER CH4104K1B00
J 0
(-6525 5875);
DISPLAY 0.808511 (-6525 5875);
DISPLAY INVISIBLE (-6525 5875);
FORCEADD Q_RES..2
(-6525 1150);
FORCEPROP 1 LAST LOCATION R6170
J 0
(-6480 1275);
DISPLAY 0.978723 (-6480 1275);
FORCEPROP 0 LAST $SEC 1
J 0
(-6475 1325);
DISPLAY 0.680851 (-6475 1325);
PAINT MONO (-6475 1325);
DISPLAY INVISIBLE (-6475 1325);
FORCEPROP 0 LAST CDS_SEC 1
J 0
(-6475 1325);
DISPLAY 0.680851 (-6475 1325);
DISPLAY INVISIBLE (-6475 1325);
FORCEPROP 1 LASTPIN (-6525 1250) $PN 1
J 0
(-6520 1212);
DISPLAY 0.787234 (-6520 1212);
PAINT MONO (-6520 1212);
FORCEPROP 1 LASTPIN (-6525 1050) $PN 2
J 0
(-6520 1060);
DISPLAY 0.787234 (-6520 1060);
PAINT MONO (-6520 1060);
FORCEPROP 1 LAST PACK_TYPE 0402LF
J 0
(-6485 975);
DISPLAY 0.638298 (-6485 975);
FORCEPROP 1 LAST VALUE 1K
J 0
(-6480 1225);
DISPLAY 0.638298 (-6480 1225);
FORCEPROP 1 LAST TOLERANCE 1%
J 0
(-6480 1175);
DISPLAY 0.638298 (-6480 1175);
FORCEPROP 1 LAST MATERIAL CHIP
J 0
(-6485 1075);
DISPLAY 0.638298 (-6485 1075);
FORCEPROP 1 LAST WATTAGE 1/16W
J 0
(-6485 1125);
DISPLAY 0.638298 (-6485 1125);
FORCEPROP 2 LAST ROOM PCIE REDRIVER BOM2
J 0
(-6475 1325);
DISPLAY 0.553191 (-6475 1325);
PAINT RED (-6475 1325);
FORCEPROP 2 LAST CDS_LIB pure_quanta
J 0
(-6525 1150);
DISPLAY INVISIBLE (-6525 1150);
FORCEPROP 1 LAST PATH I60
J 0
(-6475 1325);
DISPLAY 0.978723 (-6475 1325);
PAINT WHITE (-6475 1325);
DISPLAY INVISIBLE (-6475 1325);
FORCEPROP 1 LAST PART_NUMBER CS21002FB06
J 0
(-6485 1025);
DISPLAY 0.638298 (-6485 1025);
DISPLAY INVISIBLE (-6485 1025);
FORCEADD OFFPAGE..2
(-3950 1325);
FORCEPROP 2 LAST $XR0 112 
J 0
(-3761 1325);
DISPLAY 0.638298 (-3761 1325);
PAINT MONO (-3761 1325);
FORCEPROP 2 LAST CDS_LIB standard
J 0
(-3950 1325);
DISPLAY INVISIBLE (-3950 1325);
FORCEPROP 1 LAST OFFPAGE TRUE
J 0
(-3625 1200);
DISPLAY 0.872340 (-3625 1200);
PAINT AQUA (-3625 1200);
DISPLAY INVISIBLE (-3625 1200);
FORCEPROP 1 LAST COMMENT_BODY TRUE
J 0
(-3995 1230);
DISPLAY 0.872340 (-3995 1230);
PAINT GREEN (-3995 1230);
DISPLAY INVISIBLE (-3995 1230);
FORCEPROP 2 LAST PATH I61
J 0
(-3775 1400);
DISPLAY 0.680851 (-3775 1400);
DISPLAY INVISIBLE (-3775 1400);
FORCEADD Q_RES..2
(-4825 1625);
FORCEPROP 1 LAST LOCATION R6175
J 0
(-4780 1750);
DISPLAY 0.978723 (-4780 1750);
FORCEPROP 0 LAST $SEC 1
J 0
(-4775 1800);
DISPLAY 0.680851 (-4775 1800);
PAINT MONO (-4775 1800);
DISPLAY INVISIBLE (-4775 1800);
FORCEPROP 0 LAST CDS_SEC 1
J 0
(-4775 1800);
DISPLAY 0.680851 (-4775 1800);
DISPLAY INVISIBLE (-4775 1800);
FORCEPROP 1 LASTPIN (-4825 1725) $PN 1
J 0
(-4820 1687);
DISPLAY 0.787234 (-4820 1687);
PAINT MONO (-4820 1687);
FORCEPROP 1 LASTPIN (-4825 1525) $PN 2
J 0
(-4820 1535);
DISPLAY 0.787234 (-4820 1535);
PAINT MONO (-4820 1535);
FORCEPROP 1 LAST PACK_TYPE 0402LF
J 0
(-4785 1450);
DISPLAY 0.638298 (-4785 1450);
FORCEPROP 1 LAST MATERIAL EMPTY
J 0
(-4785 1550);
DISPLAY 0.638298 (-4785 1550);
FORCEPROP 1 LAST TOLERANCE 1%
J 0
(-4780 1650);
DISPLAY 0.638298 (-4780 1650);
FORCEPROP 1 LAST WATTAGE 1/16W
J 0
(-4785 1600);
DISPLAY 0.638298 (-4785 1600);
FORCEPROP 1 LAST VALUE 1K
J 0
(-4780 1700);
DISPLAY 0.638298 (-4780 1700);
FORCEPROP 2 LAST ROOM PCIE REDRIVER BOM2
J 0
(-4775 1800);
DISPLAY 0.680851 (-4775 1800);
PAINT RED (-4775 1800);
FORCEPROP 2 LAST CDS_LIB pure_quanta
J 0
(-4825 1625);
DISPLAY INVISIBLE (-4825 1625);
FORCEPROP 1 LAST PATH I63
J 0
(-4775 1800);
DISPLAY 0.978723 (-4775 1800);
PAINT WHITE (-4775 1800);
DISPLAY INVISIBLE (-4775 1800);
FORCEPROP 1 LAST PART_NUMBER CS21002FB06
J 0
(-4785 1500);
DISPLAY 0.638298 (-4785 1500);
DISPLAY INVISIBLE (-4785 1500);
FORCEADD Q_RES..2
(-4825 1050);
FORCEPROP 1 LAST LOCATION R6176
J 0
(-4780 1175);
DISPLAY 0.978723 (-4780 1175);
FORCEPROP 0 LAST $SEC 1
J 0
(-4775 1225);
DISPLAY 0.680851 (-4775 1225);
PAINT MONO (-4775 1225);
DISPLAY INVISIBLE (-4775 1225);
FORCEPROP 0 LAST CDS_SEC 1
J 0
(-4775 1225);
DISPLAY 0.680851 (-4775 1225);
DISPLAY INVISIBLE (-4775 1225);
FORCEPROP 1 LASTPIN (-4825 1150) $PN 1
J 0
(-4820 1112);
DISPLAY 0.787234 (-4820 1112);
PAINT MONO (-4820 1112);
FORCEPROP 1 LASTPIN (-4825 950) $PN 2
J 0
(-4820 960);
DISPLAY 0.787234 (-4820 960);
PAINT MONO (-4820 960);
FORCEPROP 1 LAST PACK_TYPE 0402LF
J 0
(-4785 875);
DISPLAY 0.638298 (-4785 875);
FORCEPROP 1 LAST MATERIAL EMPTY
J 0
(-4785 975);
DISPLAY 0.638298 (-4785 975);
FORCEPROP 1 LAST TOLERANCE 1%
J 0
(-4780 1075);
DISPLAY 0.638298 (-4780 1075);
FORCEPROP 1 LAST WATTAGE 1/16W
J 0
(-4785 1025);
DISPLAY 0.638298 (-4785 1025);
FORCEPROP 1 LAST VALUE 1K
J 0
(-4780 1125);
DISPLAY 0.638298 (-4780 1125);
FORCEPROP 2 LAST ROOM PCIE REDRIVER BOM2
J 0
(-4775 1225);
DISPLAY 0.680851 (-4775 1225);
PAINT RED (-4775 1225);
FORCEPROP 2 LAST CDS_LIB pure_quanta
J 0
(-4825 1050);
DISPLAY INVISIBLE (-4825 1050);
FORCEPROP 1 LAST PATH I64
J 0
(-4775 1225);
DISPLAY 0.978723 (-4775 1225);
PAINT WHITE (-4775 1225);
DISPLAY INVISIBLE (-4775 1225);
FORCEPROP 1 LAST PART_NUMBER CS21002FB06
J 0
(-4785 925);
DISPLAY 0.638298 (-4785 925);
DISPLAY INVISIBLE (-4785 925);
FORCEADD UNIVERSAL_GND..1
(-4825 600);
FORCEPROP 3 LASTPIN (-4825 650) SIG_NAME GND\g
J 0
(-4815 660);
DISPLAY 0.659574 (-4815 660);
PAINT MONO (-4815 660);
DISPLAY INVISIBLE (-4815 660);
FORCEPROP 2 LAST CDS_LIB pure_quanta_power
J 0
(-4825 600);
DISPLAY INVISIBLE (-4825 600);
FORCEPROP 1 LAST HDL_POWER GND
J 1
(-4800 525);
DISPLAY 0.872340 (-4800 525);
PAINT GREEN (-4800 525);
DISPLAY INVISIBLE (-4800 525);
FORCEPROP 1 LAST PATH I65
J 0
(-4750 600);
DISPLAY 0.872340 (-4750 600);
PAINT AQUA (-4750 600);
DISPLAY INVISIBLE (-4750 600);
FORCEADD UNIVERSAL_POWER..1
(-4825 1950);
FORCEPROP 3 LASTPIN (-4825 1900) SIG_NAME P3V3_AUX\g
J 0
(-4815 1910);
DISPLAY 0.659574 (-4815 1910);
PAINT MONO (-4815 1910);
DISPLAY INVISIBLE (-4815 1910);
FORCEPROP 1 LAST HDL_POWER P3V3_AUX
J 1
(-4825 2000);
DISPLAY 0.872340 (-4825 2000);
PAINT GREEN (-4825 2000);
FORCEPROP 2 LAST CDS_LIB pure_quanta_power
J 0
(-4825 1950);
DISPLAY INVISIBLE (-4825 1950);
FORCEPROP 1 LAST PATH I66
J 0
(-4775 1975);
DISPLAY 0.872340 (-4775 1975);
PAINT AQUA (-4775 1975);
DISPLAY INVISIBLE (-4775 1975);
FORCEADD UNIVERSAL_GND..1
(-3475 625);
FORCEPROP 3 LASTPIN (-3475 675) SIG_NAME GND\g
J 0
(-3465 685);
DISPLAY 0.659574 (-3465 685);
PAINT MONO (-3465 685);
DISPLAY INVISIBLE (-3465 685);
FORCEPROP 2 LAST CDS_LIB pure_quanta_power
J 0
(-3475 625);
DISPLAY INVISIBLE (-3475 625);
FORCEPROP 1 LAST HDL_POWER GND
J 1
(-3450 550);
DISPLAY 0.872340 (-3450 550);
PAINT GREEN (-3450 550);
DISPLAY INVISIBLE (-3450 550);
FORCEPROP 1 LAST PATH I67
J 0
(-3400 625);
DISPLAY 0.872340 (-3400 625);
PAINT AQUA (-3400 625);
DISPLAY INVISIBLE (-3400 625);
FORCEADD Q_RES..2
(-3475 1075);
FORCEPROP 1 LAST LOCATION R6178
J 0
(-3430 1200);
DISPLAY 0.978723 (-3430 1200);
FORCEPROP 0 LAST $SEC 1
J 0
(-3425 1250);
DISPLAY 0.680851 (-3425 1250);
PAINT MONO (-3425 1250);
DISPLAY INVISIBLE (-3425 1250);
FORCEPROP 0 LAST CDS_SEC 1
J 0
(-3425 1250);
DISPLAY 0.680851 (-3425 1250);
DISPLAY INVISIBLE (-3425 1250);
FORCEPROP 1 LASTPIN (-3475 1175) $PN 1
J 0
(-3470 1137);
DISPLAY 0.787234 (-3470 1137);
PAINT MONO (-3470 1137);
FORCEPROP 1 LASTPIN (-3475 975) $PN 2
J 0
(-3470 985);
DISPLAY 0.787234 (-3470 985);
PAINT MONO (-3470 985);
FORCEPROP 1 LAST VALUE 1K
J 0
(-3430 1150);
DISPLAY 0.638298 (-3430 1150);
FORCEPROP 1 LAST MATERIAL EMPTY
J 0
(-3435 1000);
DISPLAY 0.638298 (-3435 1000);
FORCEPROP 1 LAST WATTAGE 1/16W
J 0
(-3435 1050);
DISPLAY 0.638298 (-3435 1050);
FORCEPROP 1 LAST PACK_TYPE 0402LF
J 0
(-3435 900);
DISPLAY 0.638298 (-3435 900);
FORCEPROP 1 LAST TOLERANCE 1%
J 0
(-3430 1100);
DISPLAY 0.638298 (-3430 1100);
FORCEPROP 2 LAST ROOM PCIE REDRIVER BOM2
J 0
(-3425 1250);
DISPLAY 0.680851 (-3425 1250);
PAINT RED (-3425 1250);
FORCEPROP 2 LAST CDS_LIB pure_quanta
J 0
(-3475 1075);
DISPLAY INVISIBLE (-3475 1075);
FORCEPROP 1 LAST PATH I68
J 0
(-3425 1250);
DISPLAY 0.978723 (-3425 1250);
PAINT WHITE (-3425 1250);
DISPLAY INVISIBLE (-3425 1250);
FORCEPROP 1 LAST PART_NUMBER CS21002FB06
J 0
(-3435 950);
DISPLAY 0.638298 (-3435 950);
DISPLAY INVISIBLE (-3435 950);
FORCEADD Q_CAP..1
(-6025 6025);
FORCEPROP 1 LAST LOCATION C6012
J 0
(-5975 6125);
DISPLAY 0.638298 (-5975 6125);
FORCEPROP 0 LAST $SEC 1
J 0
(-5975 6175);
DISPLAY 0.680851 (-5975 6175);
PAINT MONO (-5975 6175);
DISPLAY INVISIBLE (-5975 6175);
FORCEPROP 0 LAST CDS_SEC 1
J 0
(-5975 6175);
DISPLAY 0.680851 (-5975 6175);
DISPLAY INVISIBLE (-5975 6175);
FORCEPROP 1 LASTPIN (-6025 6125) $PN 1
J 0
(-6015 6105);
DISPLAY 0.787234 (-6015 6105);
PAINT MONO (-6015 6105);
FORCEPROP 1 LASTPIN (-6025 5925) $PN 2
J 0
(-6015 5905);
DISPLAY 0.787234 (-6015 5905);
PAINT MONO (-6015 5905);
FORCEPROP 1 LAST VALUE 0.1UF
J 0
(-5975 6075);
DISPLAY 0.510638 (-5975 6075);
FORCEPROP 1 LAST VOLTAGE 25V
J 0
(-5975 6025);
DISPLAY 0.510638 (-5975 6025);
FORCEPROP 1 LAST TOLERANCE 10%
J 0
(-5975 5975);
DISPLAY 0.510638 (-5975 5975);
FORCEPROP 1 LAST PACK_TYPE 0402
J 0
(-5975 5875);
DISPLAY 0.510638 (-5975 5875);
FORCEPROP 1 LAST MATERIAL X7R
J 0
(-5975 5925);
DISPLAY 0.510638 (-5975 5925);
FORCEPROP 2 LAST ROOM PCIE REDRIVER BOM2
J 0
(-5975 6175);
DISPLAY 0.553191 (-5975 6175);
PAINT RED (-5975 6175);
FORCEPROP 2 LAST CDS_LIB pure_quanta
J 0
(-6025 6025);
DISPLAY INVISIBLE (-6025 6025);
FORCEPROP 1 LAST PATH I7
J 0
(-5975 6175);
DISPLAY 0.978723 (-5975 6175);
PAINT WHITE (-5975 6175);
DISPLAY INVISIBLE (-5975 6175);
FORCEPROP 1 LAST PART_NUMBER CH4104K1B00
J 0
(-5975 5875);
DISPLAY 0.808511 (-5975 5875);
DISPLAY INVISIBLE (-5975 5875);
FORCEADD UNIVERSAL_POWER..1
(-3475 1975);
FORCEPROP 3 LASTPIN (-3475 1925) SIG_NAME P3V3_AUX\g
J 0
(-3465 1935);
DISPLAY 0.659574 (-3465 1935);
PAINT MONO (-3465 1935);
DISPLAY INVISIBLE (-3465 1935);
FORCEPROP 1 LAST HDL_POWER P3V3_AUX
J 1
(-3475 2025);
DISPLAY 0.872340 (-3475 2025);
PAINT GREEN (-3475 2025);
FORCEPROP 2 LAST CDS_LIB pure_quanta_power
J 0
(-3475 1975);
DISPLAY INVISIBLE (-3475 1975);
FORCEPROP 1 LAST PATH I70
J 0
(-3425 2000);
DISPLAY 0.872340 (-3425 2000);
PAINT AQUA (-3425 2000);
DISPLAY INVISIBLE (-3425 2000);
FORCEADD OFFPAGE..2
(-2600 1350);
FORCEPROP 2 LAST $XR0 112 
J 0
(-2411 1350);
DISPLAY 0.638298 (-2411 1350);
PAINT MONO (-2411 1350);
FORCEPROP 2 LAST CDS_LIB standard
J 0
(-2600 1350);
DISPLAY INVISIBLE (-2600 1350);
FORCEPROP 1 LAST OFFPAGE TRUE
J 0
(-2275 1225);
DISPLAY 0.872340 (-2275 1225);
PAINT AQUA (-2275 1225);
DISPLAY INVISIBLE (-2275 1225);
FORCEPROP 1 LAST COMMENT_BODY TRUE
J 0
(-2645 1255);
DISPLAY 0.872340 (-2645 1255);
PAINT GREEN (-2645 1255);
DISPLAY INVISIBLE (-2645 1255);
FORCEPROP 2 LAST PATH I71
J 0
(-2425 1425);
DISPLAY 0.680851 (-2425 1425);
DISPLAY INVISIBLE (-2425 1425);
FORCEADD UNIVERSAL_GND..1
(-2125 600);
FORCEPROP 3 LASTPIN (-2125 650) SIG_NAME GND\g
J 0
(-2115 660);
DISPLAY 0.659574 (-2115 660);
PAINT MONO (-2115 660);
DISPLAY INVISIBLE (-2115 660);
FORCEPROP 2 LAST CDS_LIB pure_quanta_power
J 0
(-2125 600);
DISPLAY INVISIBLE (-2125 600);
FORCEPROP 1 LAST HDL_POWER GND
J 1
(-2100 525);
DISPLAY 0.872340 (-2100 525);
PAINT GREEN (-2100 525);
DISPLAY INVISIBLE (-2100 525);
FORCEPROP 1 LAST PATH I72
J 0
(-2050 600);
DISPLAY 0.872340 (-2050 600);
PAINT AQUA (-2050 600);
DISPLAY INVISIBLE (-2050 600);
FORCEADD Q_RES..2
(-2125 1050);
FORCEPROP 1 LAST LOCATION R6180
J 0
(-2080 1175);
DISPLAY 0.978723 (-2080 1175);
FORCEPROP 0 LAST $SEC 1
J 0
(-2075 1225);
DISPLAY 0.680851 (-2075 1225);
PAINT MONO (-2075 1225);
DISPLAY INVISIBLE (-2075 1225);
FORCEPROP 0 LAST CDS_SEC 1
J 0
(-2075 1225);
DISPLAY 0.680851 (-2075 1225);
DISPLAY INVISIBLE (-2075 1225);
FORCEPROP 1 LASTPIN (-2125 1150) $PN 1
J 0
(-2120 1112);
DISPLAY 0.787234 (-2120 1112);
PAINT MONO (-2120 1112);
FORCEPROP 1 LASTPIN (-2125 950) $PN 2
J 0
(-2120 960);
DISPLAY 0.787234 (-2120 960);
PAINT MONO (-2120 960);
FORCEPROP 1 LAST PACK_TYPE 0402LF
J 0
(-2085 875);
DISPLAY 0.638298 (-2085 875);
FORCEPROP 1 LAST VALUE 1K
J 0
(-2080 1125);
DISPLAY 0.638298 (-2080 1125);
FORCEPROP 1 LAST MATERIAL EMPTY
J 0
(-2085 975);
DISPLAY 0.638298 (-2085 975);
FORCEPROP 1 LAST TOLERANCE 1%
J 0
(-2080 1075);
DISPLAY 0.638298 (-2080 1075);
FORCEPROP 1 LAST WATTAGE 1/16W
J 0
(-2085 1025);
DISPLAY 0.638298 (-2085 1025);
FORCEPROP 2 LAST ROOM PCIE REDRIVER BOM2
J 0
(-2075 1225);
DISPLAY 0.680851 (-2075 1225);
PAINT RED (-2075 1225);
FORCEPROP 2 LAST CDS_LIB pure_quanta
J 0
(-2125 1050);
DISPLAY INVISIBLE (-2125 1050);
FORCEPROP 1 LAST PATH I73
J 0
(-2075 1225);
DISPLAY 0.978723 (-2075 1225);
PAINT WHITE (-2075 1225);
DISPLAY INVISIBLE (-2075 1225);
FORCEPROP 1 LAST PART_NUMBER CS21002FB06
J 0
(-2085 925);
DISPLAY 0.638298 (-2085 925);
DISPLAY INVISIBLE (-2085 925);
FORCEADD UNIVERSAL_POWER..1
(-2125 1950);
FORCEPROP 3 LASTPIN (-2125 1900) SIG_NAME P3V3_AUX\g
J 0
(-2115 1910);
DISPLAY 0.659574 (-2115 1910);
PAINT MONO (-2115 1910);
DISPLAY INVISIBLE (-2115 1910);
FORCEPROP 1 LAST HDL_POWER P3V3_AUX
J 1
(-2125 2000);
DISPLAY 0.872340 (-2125 2000);
PAINT GREEN (-2125 2000);
FORCEPROP 2 LAST CDS_LIB pure_quanta_power
J 0
(-2125 1950);
DISPLAY INVISIBLE (-2125 1950);
FORCEPROP 1 LAST PATH I75
J 0
(-2075 1975);
DISPLAY 0.872340 (-2075 1975);
PAINT AQUA (-2075 1975);
DISPLAY INVISIBLE (-2075 1975);
FORCEADD OFFPAGE..2
(-1250 1325);
FORCEPROP 2 LAST $XR0 112 
J 0
(-1061 1325);
DISPLAY 0.638298 (-1061 1325);
PAINT MONO (-1061 1325);
FORCEPROP 2 LAST CDS_LIB standard
J 0
(-1250 1325);
DISPLAY INVISIBLE (-1250 1325);
FORCEPROP 1 LAST OFFPAGE TRUE
J 0
(-925 1200);
DISPLAY 0.872340 (-925 1200);
PAINT AQUA (-925 1200);
DISPLAY INVISIBLE (-925 1200);
FORCEPROP 1 LAST COMMENT_BODY TRUE
J 0
(-1295 1230);
DISPLAY 0.872340 (-1295 1230);
PAINT GREEN (-1295 1230);
DISPLAY INVISIBLE (-1295 1230);
FORCEPROP 2 LAST PATH I76
J 0
(-1075 1400);
DISPLAY 0.680851 (-1075 1400);
DISPLAY INVISIBLE (-1075 1400);
FORCEADD Q_RES..2
(-3475 1650);
FORCEPROP 1 LAST LOCATION R6177
J 0
(-3430 1775);
DISPLAY 0.978723 (-3430 1775);
FORCEPROP 0 LAST $SEC 1
J 0
(-3425 1825);
DISPLAY 0.680851 (-3425 1825);
PAINT MONO (-3425 1825);
DISPLAY INVISIBLE (-3425 1825);
FORCEPROP 0 LAST CDS_SEC 1
J 0
(-3425 1825);
DISPLAY 0.680851 (-3425 1825);
DISPLAY INVISIBLE (-3425 1825);
FORCEPROP 1 LASTPIN (-3475 1750) $PN 1
J 0
(-3470 1712);
DISPLAY 0.787234 (-3470 1712);
PAINT MONO (-3470 1712);
FORCEPROP 1 LASTPIN (-3475 1550) $PN 2
J 0
(-3470 1560);
DISPLAY 0.787234 (-3470 1560);
PAINT MONO (-3470 1560);
FORCEPROP 1 LAST MATERIAL CHIP
J 0
(-3435 1575);
DISPLAY 0.638298 (-3435 1575);
FORCEPROP 1 LAST PACK_TYPE 0402LF
J 0
(-3435 1475);
DISPLAY 0.638298 (-3435 1475);
FORCEPROP 1 LAST TOLERANCE 1%
J 0
(-3430 1675);
DISPLAY 0.638298 (-3430 1675);
FORCEPROP 1 LAST VALUE 1K
J 0
(-3430 1725);
DISPLAY 0.638298 (-3430 1725);
FORCEPROP 1 LAST WATTAGE 1/16W
J 0
(-3435 1625);
DISPLAY 0.638298 (-3435 1625);
FORCEPROP 2 LAST ROOM PCIE REDRIVER BOM2
J 0
(-3425 1825);
DISPLAY 0.680851 (-3425 1825);
PAINT RED (-3425 1825);
FORCEPROP 2 LAST CDS_LIB pure_quanta
J 0
(-3475 1650);
DISPLAY INVISIBLE (-3475 1650);
FORCEPROP 1 LAST PATH I77
J 0
(-3425 1825);
DISPLAY 0.978723 (-3425 1825);
PAINT WHITE (-3425 1825);
DISPLAY INVISIBLE (-3425 1825);
FORCEPROP 1 LAST PART_NUMBER CS21002FB06
J 0
(-3435 1525);
DISPLAY 0.638298 (-3435 1525);
DISPLAY INVISIBLE (-3435 1525);
FORCEADD Q_RES..2
(-2125 1625);
FORCEPROP 1 LAST LOCATION R6179
J 0
(-2080 1750);
DISPLAY 0.978723 (-2080 1750);
FORCEPROP 0 LAST $SEC 1
J 0
(-2075 1800);
DISPLAY 0.680851 (-2075 1800);
PAINT MONO (-2075 1800);
DISPLAY INVISIBLE (-2075 1800);
FORCEPROP 0 LAST CDS_SEC 1
J 0
(-2075 1800);
DISPLAY 0.680851 (-2075 1800);
DISPLAY INVISIBLE (-2075 1800);
FORCEPROP 1 LASTPIN (-2125 1725) $PN 1
J 0
(-2120 1687);
DISPLAY 0.787234 (-2120 1687);
PAINT MONO (-2120 1687);
FORCEPROP 1 LASTPIN (-2125 1525) $PN 2
J 0
(-2120 1535);
DISPLAY 0.787234 (-2120 1535);
PAINT MONO (-2120 1535);
FORCEPROP 1 LAST MATERIAL CHIP
J 0
(-2085 1550);
DISPLAY 0.638298 (-2085 1550);
FORCEPROP 1 LAST TOLERANCE 1%
J 0
(-2080 1650);
DISPLAY 0.638298 (-2080 1650);
FORCEPROP 1 LAST VALUE 1K
J 0
(-2080 1700);
DISPLAY 0.638298 (-2080 1700);
FORCEPROP 1 LAST WATTAGE 1/16W
J 0
(-2085 1600);
DISPLAY 0.638298 (-2085 1600);
FORCEPROP 1 LAST PACK_TYPE 0402LF
J 0
(-2085 1450);
DISPLAY 0.638298 (-2085 1450);
FORCEPROP 2 LAST ROOM PCIE REDRIVER BOM2
J 0
(-2075 1800);
DISPLAY 0.680851 (-2075 1800);
PAINT RED (-2075 1800);
FORCEPROP 2 LAST CDS_LIB pure_quanta
J 0
(-2125 1625);
DISPLAY INVISIBLE (-2125 1625);
FORCEPROP 1 LAST PATH I78
J 0
(-2075 1800);
DISPLAY 0.978723 (-2075 1800);
PAINT WHITE (-2075 1800);
DISPLAY INVISIBLE (-2075 1800);
FORCEPROP 1 LAST PART_NUMBER CS21002FB06
J 0
(-2085 1500);
DISPLAY 0.638298 (-2085 1500);
DISPLAY INVISIBLE (-2085 1500);
FORCEADD OFFPAGE..4
R 2
(-6800 5625);
FORCEPROP 2 LAST $XR0 112 
J 0
(-7082 5625);
DISPLAY 0.638298 (-7082 5625);
PAINT MONO (-7082 5625);
FORCEPROP 2 LAST CDS_LIB standard
J 0
(-6800 5625);
DISPLAY INVISIBLE (-6800 5625);
FORCEPROP 1 LAST OFFPAGE TRUE
J 2
(-7125 5500);
DISPLAY 0.872340 (-7125 5500);
PAINT GREEN (-7125 5500);
DISPLAY INVISIBLE (-7125 5500);
FORCEPROP 1 LAST COMMENT_BODY TRUE
J 2
(-6775 5525);
DISPLAY 0.872340 (-6775 5525);
PAINT GREEN (-6775 5525);
DISPLAY INVISIBLE (-6775 5525);
FORCEPROP 2 LAST PATH I8
J 0
(-6750 5700);
DISPLAY 0.680851 (-6750 5700);
DISPLAY INVISIBLE (-6750 5700);
FORCEADD OFFPAGE..4
R 2
(-6800 5575);
FORCEPROP 2 LAST $XR0 112 
J 0
(-7082 5575);
DISPLAY 0.638298 (-7082 5575);
PAINT MONO (-7082 5575);
FORCEPROP 2 LAST CDS_LIB standard
J 0
(-6800 5575);
DISPLAY INVISIBLE (-6800 5575);
FORCEPROP 1 LAST OFFPAGE TRUE
J 2
(-7125 5450);
DISPLAY 0.872340 (-7125 5450);
PAINT GREEN (-7125 5450);
DISPLAY INVISIBLE (-7125 5450);
FORCEPROP 1 LAST COMMENT_BODY TRUE
J 2
(-6775 5475);
DISPLAY 0.872340 (-6775 5475);
PAINT GREEN (-6775 5475);
DISPLAY INVISIBLE (-6775 5475);
FORCEPROP 2 LAST PATH I9
J 0
(-6750 5650);
DISPLAY 0.680851 (-6750 5650);
DISPLAY INVISIBLE (-6750 5650);
FORCEADD DNS..2
(-6525 2825);
PAINT RED (-6525 2825);
FORCEPROP 2 LAST CDS_LIB mstr_misc
J 0
(-6525 2825);
DISPLAY INVISIBLE (-6525 2825);
FORCEPROP 1 LAST COMMENT_BODY TRUE
R 1
J 0
(-6450 2600);
DISPLAY 0.872340 (-6450 2600);
PAINT GREEN (-6450 2600);
DISPLAY INVISIBLE (-6450 2600);
FORCEADD DNS..2
(-3450 1050);
PAINT RED (-3450 1050);
FORCEPROP 2 LAST CDS_LIB mstr_misc
J 0
(-3450 1050);
DISPLAY INVISIBLE (-3450 1050);
FORCEPROP 1 LAST COMMENT_BODY TRUE
R 1
J 0
(-3375 825);
DISPLAY 0.872340 (-3375 825);
PAINT GREEN (-3375 825);
DISPLAY INVISIBLE (-3375 825);
FORCEADD DNS..2
(-4800 1025);
PAINT RED (-4800 1025);
FORCEPROP 2 LAST CDS_LIB mstr_misc
J 0
(-4800 1025);
DISPLAY INVISIBLE (-4800 1025);
FORCEPROP 1 LAST COMMENT_BODY TRUE
R 1
J 0
(-4725 800);
DISPLAY 0.872340 (-4725 800);
PAINT GREEN (-4725 800);
DISPLAY INVISIBLE (-4725 800);
FORCEADD DNS..2
(-6975 1750);
PAINT RED (-6975 1750);
FORCEPROP 2 LAST CDS_LIB mstr_misc
J 0
(-6975 1750);
DISPLAY INVISIBLE (-6975 1750);
FORCEPROP 1 LAST COMMENT_BODY TRUE
R 1
J 0
(-6900 1525);
DISPLAY 0.872340 (-6900 1525);
PAINT GREEN (-6900 1525);
DISPLAY INVISIBLE (-6900 1525);
FORCEADD DNS..2
(-5075 3450);
PAINT RED (-5075 3450);
FORCEPROP 2 LAST CDS_LIB mstr_misc
J 0
(-5075 3450);
DISPLAY INVISIBLE (-5075 3450);
FORCEPROP 1 LAST COMMENT_BODY TRUE
R 1
J 0
(-5000 3225);
DISPLAY 0.872340 (-5000 3225);
PAINT GREEN (-5000 3225);
DISPLAY INVISIBLE (-5000 3225);
FORCEADD DNS..2
(-4800 1625);
PAINT RED (-4800 1625);
FORCEPROP 2 LAST CDS_LIB mstr_misc
J 0
(-4800 1625);
DISPLAY INVISIBLE (-4800 1625);
FORCEPROP 1 LAST COMMENT_BODY TRUE
R 1
J 0
(-4725 1400);
DISPLAY 0.872340 (-4725 1400);
PAINT GREEN (-4725 1400);
DISPLAY INVISIBLE (-4725 1400);
FORCEADD DNS..2
(-4600 3425);
PAINT RED (-4600 3425);
FORCEPROP 2 LAST CDS_LIB mstr_misc
J 0
(-4600 3425);
DISPLAY INVISIBLE (-4600 3425);
FORCEPROP 1 LAST COMMENT_BODY TRUE
R 1
J 0
(-4525 3200);
DISPLAY 0.872340 (-4525 3200);
PAINT GREEN (-4525 3200);
DISPLAY INVISIBLE (-4525 3200);
FORCEADD DNS..2
(-2100 1025);
PAINT RED (-2100 1025);
FORCEPROP 2 LAST CDS_LIB mstr_misc
J 0
(-2100 1025);
DISPLAY INVISIBLE (-2100 1025);
FORCEPROP 1 LAST COMMENT_BODY TRUE
R 1
J 0
(-2025 800);
DISPLAY 0.872340 (-2025 800);
PAINT GREEN (-2025 800);
DISPLAY INVISIBLE (-2025 800);
FORCEADD DNS..2
(-6500 1725);
PAINT RED (-6500 1725);
FORCEPROP 2 LAST CDS_LIB mstr_misc
J 0
(-6500 1725);
DISPLAY INVISIBLE (-6500 1725);
FORCEPROP 1 LAST COMMENT_BODY TRUE
R 1
J 0
(-6425 1500);
DISPLAY 0.872340 (-6425 1500);
PAINT GREEN (-6425 1500);
DISPLAY INVISIBLE (-6425 1500);
FORCEADD DNS..2
(-6525 3425);
PAINT RED (-6525 3425);
FORCEPROP 2 LAST CDS_LIB mstr_misc
J 0
(-6525 3425);
DISPLAY INVISIBLE (-6525 3425);
FORCEPROP 1 LAST COMMENT_BODY TRUE
R 1
J 0
(-6450 3200);
DISPLAY 0.872340 (-6450 3200);
PAINT GREEN (-6450 3200);
DISPLAY INVISIBLE (-6450 3200);
FORCEADD DNS..2
(-7000 3450);
PAINT RED (-7000 3450);
FORCEPROP 2 LAST CDS_LIB mstr_misc
J 0
(-7000 3450);
DISPLAY INVISIBLE (-7000 3450);
FORCEPROP 1 LAST COMMENT_BODY TRUE
R 1
J 0
(-6925 3225);
DISPLAY 0.872340 (-6925 3225);
PAINT GREEN (-6925 3225);
DISPLAY INVISIBLE (-6925 3225);
FORCEADD DNS..2
(-4600 2825);
PAINT RED (-4600 2825);
FORCEPROP 2 LAST CDS_LIB mstr_misc
J 0
(-4600 2825);
DISPLAY INVISIBLE (-4600 2825);
FORCEPROP 1 LAST COMMENT_BODY TRUE
R 1
J 0
(-4525 2600);
DISPLAY 0.872340 (-4525 2600);
PAINT GREEN (-4525 2600);
DISPLAY INVISIBLE (-4525 2600);
FORCEADD QUANTA_TITLE_BLOCK_C..1
(-100 100);
FORCEPROP 0 LAST CDS_CON_LAST_MODIFIED Thu Sep 14 16:12:44 2023
J 0
(-1985 115);
DISPLAY INVISIBLE (-1985 115);
FORCEPROP 1 LAST CUSTOM_TXT_CDS <CON_LAST_MODIFIED>
J 0
(-1985 115);
DISPLAY 0.978723 (-1985 115);
FORCEPROP 2 LAST CUSTOM_TXT_CDS <XR_PAGE_TITLE>
J 0
(-7990 5350);
DISPLAY 0.638298 (-7990 5350);
PAINT PINK (-7990 5350);
DISPLAY INVISIBLE (-7990 5350);
FORCEPROP 1 LAST CUSTOM_TXT_CDS <NAME_2>
J 0
(-3275 150);
FORCEPROP 1 LAST CUSTOM_TXT_CDS <NAME_1>
J 0
(-3275 275);
FORCEPROP 1 LAST CUSTOM_TXT_CDS <Q_NUMBER>
J 0
(-1503 203);
DISPLAY 1.212766 (-1503 203);
FORCEPROP 1 LAST CUSTOM_TXT_CDS <Q_PROJ>
J 0
(-2482 202);
DISPLAY 1.212766 (-2482 202);
FORCEPROP 1 LAST CUSTOM_TXT_CDS <Q_REV>
J 0
(-284 203);
DISPLAY 1.212766 (-284 203);
FORCEPROP 1 LAST CUSTOM_TXT_CDS <CON_PAGE_NUM> OF <CON_TOTAL_PAGES>
J 0
(-546 118);
DISPLAY 0.978723 (-546 118);
FORCEPROP 1 LAST Q_TITLE BMC-GPU FPGA PCIE - RE-DRIVER (2nd)
J 0
(-9400 150);
DISPLAY 2.446809 (-9400 150);
PAINT GREEN (-9400 150);
FORCEPROP 1 LAST CDS_LMAN_SYM_OUTLINE -9475,6775,100,-125
J 0
(-100 100);
DISPLAY 0.468085 (-100 100);
PAINT GREEN (-100 100);
DISPLAY INVISIBLE (-100 100);
FORCEPROP 2 LAST CDS_LIB pure_quanta
J 0
(-100 100);
DISPLAY INVISIBLE (-100 100);
FORCEPROP 2 LAST PAGE_BORDER TRUE
J 0
(-7990 5350);
DISPLAY 0.638298 (-7990 5350);
PAINT PINK (-7990 5350);
DISPLAY INVISIBLE (-7990 5350);
FORCEPROP 2 LAST CDS_XR_PAGE_TITLE CR-112 : @T6G_MB_LIB.T6G(SCH_1):PAGE112
J 0
(-7990 5350);
DISPLAY 0.638298 (-7990 5350);
PAINT PINK (-7990 5350);
DISPLAY INVISIBLE (-7990 5350);
FORCEPROP 1 LAST Q_DEPT BU9
J 1
(-3863 149);
DISPLAY 1.957447 (-3863 149);
PAINT GREEN (-3863 149);
DISPLAY INVISIBLE (-3863 149);
FORCEPROP 1 LAST COMMENT_BODY TRUE
J 0
(-88 87);
DISPLAY 0.978723 (-88 87);
PAINT GREEN (-88 87);
DISPLAY INVISIBLE (-88 87);
WIRE 16 -1 (-7525 4775)(-7525 4625);
WIRE 16 -1 (-4200 4675)(-4000 4675);
WIRE 16 -1 (-4000 4675)(-4000 4550);
WIRE 16 -1 (-7000 2750)(-7000 2450);
WIRE 16 -1 (-6550 2750)(-6550 2450);
WIRE 16 -1 (-4625 2750)(-4625 2450);
WIRE 16 -1 (-5075 2750)(-5075 2450);
WIRE 16 -1 (-6525 1050)(-6525 750);
WIRE 16 -1 (-6975 1050)(-6975 750);
WIRE 16 -1 (-4825 950)(-4825 650);
WIRE 16 -1 (-4825 1725)(-4825 1900);
WIRE 16 -1 (-3475 975)(-3475 675);
WIRE 16 -1 (-3475 1750)(-3475 1925);
WIRE 16 -1 (-2125 950)(-2125 650);
WIRE 16 -1 (-2125 1725)(-2125 1900);
WIRE 16 -1 (-5375 5925)(-5375 6300);
WIRE 16 -1 (-5375 5925)(-5250 5925);
WIRE 16 -1 (-5375 6300)(-6125 6300);
WIRE 16 -1 (-6125 6300)(-7150 6300);
WIRE 16 -1 (-6125 6300)(-6125 6375);
WIRE 16 -1 (-7150 6175)(-7150 6300);
WIRE 16 -1 (-7725 6300)(-7150 6300);
WIRE 16 -1 (-7725 6175)(-7725 6300);
WIRE 16 -1 (-1300 1325)(-2125 1325);
FORCEPROP 2 LAST SIG_NAME FM_P2E_BUF2_VOD_SEL
J 0
(-2010 1335);
DISPLAY 0.680851 (-2010 1335);
WIRE 16 -1 (-2125 1525)(-2125 1325);
WIRE 16 -1 (-2125 1325)(-2125 1150);
WIRE 16 -1 (-2650 1350)(-3475 1350);
FORCEPROP 2 LAST SIG_NAME FM_P2E_BUF2_SD_TH
J 0
(-3260 1360);
DISPLAY 0.680851 (-3260 1360);
WIRE 16 -1 (-3475 1550)(-3475 1350);
WIRE 16 -1 (-3475 1350)(-3475 1175);
WIRE 16 -1 (-4000 1325)(-4825 1325);
FORCEPROP 2 LAST SIG_NAME FM_P2E_BUF2_RXDET
J 0
(-4710 1335);
DISPLAY 0.680851 (-4710 1335);
WIRE 16 -1 (-4825 1525)(-4825 1325);
WIRE 16 -1 (-4825 1325)(-4825 1150);
WIRE 16 -1 (-3800 3200)(-5075 3200);
FORCEPROP 2 LAST SIG_NAME FM_P2E_BUF2_EQA1
J 0
(-4385 3210);
DISPLAY 0.680851 (-4385 3210);
WIRE 16 -1 (-5075 3325)(-5075 3200);
WIRE 16 -1 (-5075 3200)(-5075 2950);
WIRE 16 -1 (-3800 3125)(-4625 3125);
FORCEPROP 2 LAST SIG_NAME FM_P2E_BUF2_EQA0
J 0
(-4385 3135);
DISPLAY 0.680851 (-4385 3135);
WIRE 16 -1 (-4625 3325)(-4625 3125);
WIRE 16 -1 (-4625 3125)(-4625 2950);
WIRE 16 -1 (-6525 1950)(-6525 1825);
WIRE 16 -1 (-6975 1950)(-6525 1950);
WIRE 16 -1 (-6975 2050)(-6975 1950);
WIRE 16 -1 (-6975 1950)(-6975 1825);
WIRE 16 -1 (-5075 3650)(-4625 3650);
WIRE 16 -1 (-5075 3750)(-5075 3650);
WIRE 16 -1 (-5075 3650)(-5075 3525);
WIRE 16 -1 (-4625 3650)(-4625 3525);
WIRE 16 -1 (-6025 5925)(-6025 5725);
WIRE 16 -1 (-5250 5725)(-6025 5725);
WIRE 16 -1 (-6025 5725)(-6575 5725);
WIRE 16 -1 (-6575 5925)(-6575 5725);
WIRE 16 -1 (-6575 5725)(-6675 5725);
WIRE 16 -1 (-7150 5725)(-6675 5725);
WIRE 16 -1 (-6675 5725)(-6675 5700);
WIRE 16 -1 (-7150 5975)(-7150 5725);
WIRE 16 -1 (-7725 5725)(-7150 5725);
WIRE 16 -1 (-7725 5975)(-7725 5725);
WIRE 16 -1 (-6550 3650)(-6550 3525);
WIRE 16 -1 (-7000 3650)(-6550 3650);
WIRE 16 -1 (-7000 3750)(-7000 3650);
WIRE 16 -1 (-7000 3650)(-7000 3525);
WIRE 16 -1 (-3300 4775)(-4200 4775);
FORCEPROP 2 LAST SIG_NAME P2E_MB_BMC_RX_BUF2_C_DN<0>
J 0
(-4110 4785);
DISPLAY 0.680851 (-4110 4785);
WIRE 16 -1 (-3300 4825)(-4200 4825);
FORCEPROP 2 LAST SIG_NAME P2E_MB_BMC_RX_BUF2_C_DP<0>
J 0
(-4110 4835);
DISPLAY 0.680851 (-4110 4835);
WIRE 16 -1 (-3300 4925)(-4200 4925);
FORCEPROP 2 LAST SIG_NAME P2E_MB_BMC_TX_BUF2_DN<0>
J 0
(-4060 4935);
DISPLAY 0.680851 (-4060 4935);
WIRE 16 -1 (-3300 4975)(-4200 4975);
FORCEPROP 2 LAST SIG_NAME P2E_MB_BMC_TX_BUF2_DP<0>
J 0
(-4060 4985);
DISPLAY 0.680851 (-4060 4985);
WIRE 16 -1 (-4200 5375)(-3275 5375);
FORCEPROP 2 LAST SIG_NAME FM_P2E_BUF2_RXDET
J 0
(-3960 5385);
DISPLAY 0.680851 (-3960 5385);
WIRE 16 -1 (-4200 5225)(-3375 5225);
FORCEPROP 2 LAST SIG_NAME FM_P2E_EN2_N
J 0
(-4035 5235);
DISPLAY 0.680851 (-4035 5235);
FORCEPROP 2 LASTPROP $XRERR UNIQUE?
J 0
(-4275 5235);
DISPLAY 0.638298 (-4275 5235);
PAINT MONO (-4275 5235);
DISPLAY INVISIBLE (-4275 5235);
WIRE 16 -1 (-5700 1425)(-6525 1425);
FORCEPROP 2 LAST SIG_NAME FM_P2E_BUF2_VODA_DB
J 0
(-6335 1435);
DISPLAY 0.680851 (-6335 1435);
WIRE 16 -1 (-6525 1625)(-6525 1425);
WIRE 16 -1 (-6525 1425)(-6525 1250);
WIRE 16 -1 (-5700 1500)(-6975 1500);
FORCEPROP 2 LAST SIG_NAME FM_P2E_BUF2_VODB_DB
J 0
(-6335 1510);
DISPLAY 0.680851 (-6335 1510);
WIRE 16 -1 (-6975 1625)(-6975 1500);
WIRE 16 -1 (-6975 1500)(-6975 1250);
WIRE 16 -1 (-5725 3125)(-6550 3125);
FORCEPROP 2 LAST SIG_NAME FM_P2E_BUF2_EQB0
J 0
(-6285 3135);
DISPLAY 0.680851 (-6285 3135);
WIRE 16 -1 (-6550 3325)(-6550 3125);
WIRE 16 -1 (-6550 3125)(-6550 2950);
WIRE 16 -1 (-5725 3200)(-7000 3200);
FORCEPROP 2 LAST SIG_NAME FM_P2E_BUF2_EQB1
J 0
(-6285 3210);
DISPLAY 0.680851 (-6285 3210);
WIRE 16 -1 (-7000 3325)(-7000 3200);
WIRE 16 -1 (-7000 3200)(-7000 2950);
WIRE 16 -1 (-3175 5225)(-2175 5225);
FORCEPROP 2 LAST SIG_NAME CLK_GEN2_GPU_FPGA_OE_OR_N
J 0
(-2960 5235);
DISPLAY 0.680851 (-2960 5235);
WIRE 16 -1 (-5250 5625)(-6750 5625);
FORCEPROP 2 LAST SIG_NAME FM_P2E_BUF2_EQA0
J 0
(-6235 5635);
DISPLAY 0.680851 (-6235 5635);
WIRE 16 -1 (-5250 5575)(-6750 5575);
FORCEPROP 2 LAST SIG_NAME FM_P2E_BUF2_EQA1
J 0
(-6235 5585);
DISPLAY 0.680851 (-6235 5585);
WIRE 16 -1 (-5250 5525)(-6750 5525);
FORCEPROP 2 LAST SIG_NAME FM_P2E_BUF2_EQB1
J 0
(-6235 5535);
DISPLAY 0.680851 (-6235 5535);
WIRE 16 -1 (-6750 5475)(-5250 5475);
FORCEPROP 2 LAST SIG_NAME FM_P2E_BUF2_EQB0
J 0
(-6235 5485);
DISPLAY 0.680851 (-6235 5485);
WIRE 16 -1 (-6575 5075)(-5250 5075);
FORCEPROP 2 LAST SIG_NAME FM_P2E_BUF2_VODB_DB
J 0
(-6360 5085);
DISPLAY 0.680851 (-6360 5085);
WIRE 16 -1 (-6550 4975)(-5250 4975);
FORCEPROP 2 LAST SIG_NAME P2E_MB_BMC_TX_C_R2_DP<0>
J 0
(-6385 4985);
DISPLAY 0.680851 (-6385 4985);
WIRE 16 -1 (-6550 4925)(-5250 4925);
FORCEPROP 2 LAST SIG_NAME P2E_MB_BMC_TX_C_R2_DN<0>
J 0
(-6385 4935);
DISPLAY 0.680851 (-6385 4935);
WIRE 16 -1 (-6575 5125)(-5250 5125);
FORCEPROP 2 LAST SIG_NAME FM_P2E_BUF2_VODA_DB
J 0
(-6360 5135);
DISPLAY 0.680851 (-6360 5135);
WIRE 16 -1 (-5250 5175)(-7525 5175);
FORCEPROP 2 LAST SIG_NAME PD_P2E_BUF2_ENSMB
J 0
(-6660 5185);
DISPLAY 0.680851 (-6660 5185);
FORCEPROP 2 LASTPROP $XRERR UNIQUE?
J 0
(-6900 5185);
DISPLAY 0.638298 (-6900 5185);
PAINT MONO (-6900 5185);
DISPLAY INVISIBLE (-6900 5185);
WIRE 16 -1 (-7525 5175)(-7525 4975);
WIRE 16 -1 (-4200 5675)(-3275 5675);
FORCEPROP 2 LAST SIG_NAME FM_P2E_BUF2_SD_TH
J 0
(-3935 5685);
DISPLAY 0.680851 (-3935 5685);
WIRE 16 -1 (-6550 4825)(-5250 4825);
FORCEPROP 2 LAST SIG_NAME P2E_MB_BMC_RX_R2_DP<0>
J 0
(-6310 4835);
DISPLAY 0.680851 (-6310 4835);
WIRE 16 -1 (-6550 4775)(-5250 4775);
FORCEPROP 2 LAST SIG_NAME P2E_MB_BMC_RX_R2_DN<0>
J 0
(-6310 4785);
DISPLAY 0.680851 (-6310 4785);
WIRE 16 -1 (-5450 5825)(-5250 5825);
WIRE 16 -1 (-5450 5875)(-5450 5825);
WIRE 16 -1 (-5450 6250)(-5450 5875);
WIRE 16 -1 (-5450 5875)(-5250 5875);
WIRE 16 -1 (-5450 6250)(-6025 6250);
WIRE 16 -1 (-6025 6250)(-6025 6125);
WIRE 16 -1 (-6575 6250)(-6025 6250);
FORCEPROP 2 LAST SIG_NAME BUF2_VDD
J 0
(-6510 6260);
DISPLAY 0.680851 (-6510 6260);
FORCEPROP 2 LASTPROP $XRERR UNIQUE?
J 0
(-6750 6260);
DISPLAY 0.638298 (-6750 6260);
PAINT MONO (-6750 6260);
DISPLAY INVISIBLE (-6750 6260);
WIRE 16 -1 (-6575 6125)(-6575 6250);
WIRE 16 -1 (-4200 5825)(-3275 5825);
FORCEPROP 2 LAST SIG_NAME NC_RES
J 0
(-3910 5835);
DISPLAY 0.680851 (-3910 5835);
FORCEPROP 2 LASTPROP $XRERR UNIQUE?
J 0
(-3245 5825);
DISPLAY 0.638298 (-3245 5825);
PAINT MONO (-3245 5825);
DISPLAY INVISIBLE (-3245 5825);
WIRE 16 -1 (-4200 5975)(-3275 5975);
FORCEPROP 2 LAST SIG_NAME FM_P2E_BUF2_VOD_SEL
J 0
(-3985 6010);
DISPLAY 0.680851 (-3985 6010);
DOT 1 (-4625 3125);
DOT 1 (-6525 1425);
DOT 1 (-6550 3125);
DOT 1 (-6025 5725);
DOT 1 (-7150 5725);
DOT 1 (-7150 6300);
DOT 1 (-6575 5725);
DOT 1 (-6025 6250);
CIRCLE (-7650 5425)(-7420 5425);
PAINT YELLOW (-7650 5425);
DOT 1 (-6675 5725);
DOT 1 (-5450 5875);
DOT 1 (-7000 3650);
DOT 1 (-5075 3650);
DOT 1 (-3475 1350);
DOT 1 (-2125 1325);
DOT 1 (-7000 3200);
CIRCLE (-7650 2375)(-7420 2375);
PAINT YELLOW (-7650 2375);
DOT 1 (-6975 1500);
DOT 1 (-6975 1950);
DOT 1 (-5075 3200);
DOT 1 (-4825 1325);
DOT 1 (-6125 6300);
FORCENOTE
TBC
(-7725 5400) 0;
DISPLAY LEFT (-7725 5400);
DISPLAY 1.021277 (-7725 5400);
FORCENOTE
TBC
(-7725 2350) 0;
DISPLAY LEFT (-7725 2350);
DISPLAY 1.021277 (-7725 2350);
FORCENOTE
$CDS_IMAGE|clipboard_1_18.jpg|2575|555
(-1925 3050) 0;
DISPLAY LEFT (-1925 3050);
FORCENOTE
$CDS_IMAGE|clipboard_0_29.jpg|2284|608
(-2075 3750) 0;
DISPLAY LEFT (-2075 3750);
QUIT
